FILE_TYPE = MACRO_DRAWING;
SET COLOR_WIRE YELLOW;
SET COLOR_PROP MONO;
SET COLOR_DOT WHITE;
SET COLOR_ARC YELLOW;
SET COLOR_BODY GREEN;
SET COLOR_NOTE MONO;
SET PROP_DISPLAY VALUE;
SET PAGE_NUMBER P125;
FORCEADD RES..2
(1750 3050);
FORCEPROP 1 LASTPIN (1750 2950) $PN 2
J 0
(1755 2960);
DISPLAY 0.617021 (1755 2960);
PAINT WHITE (1755 2960);
FORCEPROP 1 LAST WATTAGE 1/16W
J 0
(1790 3025);
DISPLAY 0.617021 (1790 3025);
PAINT SKYBLUE (1790 3025);
FORCEPROP 1 LAST PACK_TYPE 0402
J 0
(1790 2875);
DISPLAY 0.617021 (1790 2875);
PAINT SKYBLUE (1790 2875);
FORCEPROP 1 LAST MATERIAL EMPTY
J 0
(1790 2975);
DISPLAY 0.617021 (1790 2975);
PAINT RED (1790 2975);
FORCEPROP 1 LASTPIN (1750 3150) $PN 1
J 0
(1755 3112);
DISPLAY 0.617021 (1755 3112);
PAINT WHITE (1755 3112);
FORCEPROP 1 LAST TOLERANCE 1%
J 0
(1795 3075);
DISPLAY 0.617021 (1795 3075);
PAINT SKYBLUE (1795 3075);
FORCEPROP 1 LAST VALUE 1.00K
J 0
(1795 3125);
DISPLAY 0.617021 (1795 3125);
PAINT SKYBLUE (1795 3125);
FORCEPROP 1 LAST LOCATION R2R11
J 0
(1795 3175);
DISPLAY 0.617021 (1795 3175);
PAINT AQUA (1795 3175);
FORCEPROP 1 LAST PART_NUMBER G21796-026
J 0
(1790 2925);
DISPLAY 0.617021 (1790 2925);
PAINT BLUE (1790 2925);
FORCEPROP 2 LAST CDS_LIB mstr_discrete
J 0
(1750 3050);
PAINT ORANGE (1750 3050);
DISPLAY INVISIBLE (1750 3050);
FORCEPROP 2 LAST ROOM SB
J 0
(1800 3225);
DISPLAY 1.361702 (1800 3225);
PAINT ORANGE (1800 3225);
DISPLAY INVISIBLE (1800 3225);
FORCEPROP 1 LAST PATH I11
J 0
(1800 3225);
DISPLAY 0.978723 (1800 3225);
PAINT WHITE (1800 3225);
DISPLAY INVISIBLE (1800 3225);
FORCEPROP 2 LAST CDS_LOCATION R2R11
J 0
(1795 3175);
DISPLAY 0.617021 (1795 3175);
PAINT AQUA (1795 3175);
DISPLAY INVISIBLE (1795 3175);
FORCEPROP 2 LAST $SEC 1
J 0
(1800 3275);
DISPLAY 0.914894 (1800 3275);
PAINT MONO (1800 3275);
DISPLAY INVISIBLE (1800 3275);
FORCEPROP 2 LAST CDS_SEC 1
J 0
(1800 3275);
DISPLAY 1.361702 (1800 3275);
PAINT ORANGE (1800 3275);
DISPLAY INVISIBLE (1800 3275);
FORCEPROP 2 LAST BOM_COST SB
J 0
(1800 3225);
DISPLAY 1.361702 (1800 3225);
PAINT ORANGE (1800 3225);
DISPLAY INVISIBLE (1800 3225);
FORCEADD GND..1
(1750 2800);
FORCEPROP 3 LASTPIN (1750 2850) SIG_NAME GND\g
J 0
(1760 2860);
DISPLAY 0.659574 (1760 2860);
PAINT MONO (1760 2860);
DISPLAY INVISIBLE (1760 2860);
FORCEPROP 1 LAST BODY_TYPE PLUMBING
J 0
(1705 2757);
DISPLAY 0.340426 (1705 2757);
PAINT GREEN (1705 2757);
DISPLAY INVISIBLE (1705 2757);
FORCEPROP 1 LAST VOLTAGE 0.0V
J 0
(1705 2757);
DISPLAY 0.340426 (1705 2757);
PAINT SKYBLUE (1705 2757);
DISPLAY INVISIBLE (1705 2757);
FORCEPROP 2 LAST CDS_LIB mstr_symbols
J 0
(1750 2800);
PAINT ORANGE (1750 2800);
DISPLAY INVISIBLE (1750 2800);
FORCEPROP 2 LAST ROOM SB
J 0
(1775 2875);
DISPLAY 1.361702 (1775 2875);
PAINT ORANGE (1775 2875);
DISPLAY INVISIBLE (1775 2875);
FORCEPROP 2 LAST BOM_COST SB
J 0
(1775 2875);
DISPLAY 1.361702 (1775 2875);
PAINT ORANGE (1775 2875);
DISPLAY INVISIBLE (1775 2875);
FORCEPROP 1 LAST HDL_POWER GND
J 0
(1750 2950);
DISPLAY 1.170213 (1750 2950);
PAINT GREEN (1750 2950);
DISPLAY INVISIBLE (1750 2950);
FORCEPROP 1 LAST PATH I14
J 0
(1825 2800);
DISPLAY 0.872340 (1825 2800);
PAINT AQUA (1825 2800);
DISPLAY INVISIBLE (1825 2800);
FORCEPROP 1 LAST SIZE 1B
J 0
(1825 2750);
DISPLAY 1.170213 (1825 2750);
PAINT AQUA (1825 2750);
DISPLAY INVISIBLE (1825 2750);
FORCEADD RES..2
(1850 1475);
FORCEPROP 1 LASTPIN (1850 1375) $PN 2
J 0
(1855 1385);
DISPLAY 0.617021 (1855 1385);
PAINT WHITE (1855 1385);
FORCEPROP 1 LAST WATTAGE 1/16W
J 0
(1890 1450);
DISPLAY 0.617021 (1890 1450);
PAINT SKYBLUE (1890 1450);
FORCEPROP 1 LAST TOLERANCE 1%
J 0
(1895 1500);
DISPLAY 0.617021 (1895 1500);
PAINT SKYBLUE (1895 1500);
FORCEPROP 1 LAST PACK_TYPE 0402
J 0
(1890 1300);
DISPLAY 0.617021 (1890 1300);
PAINT SKYBLUE (1890 1300);
FORCEPROP 1 LAST MATERIAL CHIP
J 0
(1890 1400);
DISPLAY 0.617021 (1890 1400);
PAINT SKYBLUE (1890 1400);
FORCEPROP 1 LASTPIN (1850 1575) $PN 1
J 0
(1855 1537);
DISPLAY 0.617021 (1855 1537);
PAINT WHITE (1855 1537);
FORCEPROP 1 LAST VALUE 1.00K
J 0
(1895 1550);
DISPLAY 0.617021 (1895 1550);
PAINT SKYBLUE (1895 1550);
FORCEPROP 1 LAST LOCATION R2T1
J 0
(1895 1600);
DISPLAY 0.617021 (1895 1600);
PAINT AQUA (1895 1600);
FORCEPROP 1 LAST PART_NUMBER G21796-026
J 0
(1890 1350);
DISPLAY 0.617021 (1890 1350);
PAINT BLUE (1890 1350);
FORCEPROP 2 LAST CDS_LIB mstr_discrete
J 0
(1850 1475);
PAINT ORANGE (1850 1475);
DISPLAY INVISIBLE (1850 1475);
FORCEPROP 2 LAST CDS_LOCATION R2T1
J 0
(1895 1600);
DISPLAY 0.617021 (1895 1600);
PAINT AQUA (1895 1600);
DISPLAY INVISIBLE (1895 1600);
FORCEPROP 2 LAST ROOM SB
J 0
(1900 1650);
DISPLAY 1.361702 (1900 1650);
PAINT ORANGE (1900 1650);
DISPLAY INVISIBLE (1900 1650);
FORCEPROP 1 LAST PATH I15
J 0
(1900 1650);
DISPLAY 0.978723 (1900 1650);
PAINT WHITE (1900 1650);
DISPLAY INVISIBLE (1900 1650);
FORCEPROP 2 LAST BOM_COST SB
J 0
(1900 1650);
DISPLAY 1.361702 (1900 1650);
PAINT ORANGE (1900 1650);
DISPLAY INVISIBLE (1900 1650);
FORCEPROP 2 LAST $SEC 1
J 0
(1900 1700);
DISPLAY 0.914894 (1900 1700);
PAINT MONO (1900 1700);
DISPLAY INVISIBLE (1900 1700);
FORCEPROP 2 LAST CDS_SEC 1
J 0
(1900 1700);
DISPLAY 1.361702 (1900 1700);
PAINT ORANGE (1900 1700);
DISPLAY INVISIBLE (1900 1700);
FORCEADD GND..1
(1850 1225);
FORCEPROP 3 LASTPIN (1850 1275) SIG_NAME GND\g
J 0
(1860 1285);
DISPLAY 0.659574 (1860 1285);
PAINT MONO (1860 1285);
DISPLAY INVISIBLE (1860 1285);
FORCEPROP 1 LAST PATH I16
J 0
(1925 1225);
DISPLAY 0.872340 (1925 1225);
PAINT AQUA (1925 1225);
DISPLAY INVISIBLE (1925 1225);
FORCEPROP 1 LAST BODY_TYPE PLUMBING
J 0
(1805 1182);
DISPLAY 0.340426 (1805 1182);
PAINT GREEN (1805 1182);
DISPLAY INVISIBLE (1805 1182);
FORCEPROP 1 LAST SIZE 1B
J 0
(1925 1175);
DISPLAY 1.170213 (1925 1175);
PAINT AQUA (1925 1175);
DISPLAY INVISIBLE (1925 1175);
FORCEPROP 2 LAST CDS_LIB mstr_symbols
J 0
(1850 1225);
PAINT ORANGE (1850 1225);
DISPLAY INVISIBLE (1850 1225);
FORCEPROP 1 LAST VOLTAGE 0.0V
J 0
(1805 1182);
DISPLAY 0.340426 (1805 1182);
PAINT SKYBLUE (1805 1182);
DISPLAY INVISIBLE (1805 1182);
FORCEPROP 2 LAST ROOM SB
J 0
(1875 1300);
DISPLAY 1.361702 (1875 1300);
PAINT ORANGE (1875 1300);
DISPLAY INVISIBLE (1875 1300);
FORCEPROP 2 LAST BOM_COST SB
J 0
(1875 1300);
DISPLAY 1.361702 (1875 1300);
PAINT ORANGE (1875 1300);
DISPLAY INVISIBLE (1875 1300);
FORCEPROP 1 LAST HDL_POWER GND
J 0
(1850 1375);
DISPLAY 1.170213 (1850 1375);
PAINT GREEN (1850 1375);
DISPLAY INVISIBLE (1850 1375);
FORCEADD OFFPAGE..5
(650 3275);
FORCEPROP 2 LAST $XR0 111 
J 0
(365 3275);
DISPLAY 0.638298 (365 3275);
PAINT MONO (365 3275);
FORCEPROP 2 LAST $XR1 121 
J 0
(245 3275);
DISPLAY 0.638298 (245 3275);
PAINT MONO (245 3275);
FORCEPROP 2 LAST $XR2 154 
J 0
(125 3275);
DISPLAY 0.638298 (125 3275);
PAINT MONO (125 3275);
FORCEPROP 2 LAST PATH I20
J 0
(375 3325);
DISPLAY 1.021277 (375 3325);
PAINT ORANGE (375 3325);
DISPLAY INVISIBLE (375 3325);
FORCEPROP 2 LAST ROOM SB
J 0
(375 3325);
DISPLAY 1.361702 (375 3325);
PAINT ORANGE (375 3325);
DISPLAY INVISIBLE (375 3325);
FORCEPROP 2 LAST BOM_COST SB
J 0
(375 3325);
DISPLAY 1.361702 (375 3325);
PAINT ORANGE (375 3325);
DISPLAY INVISIBLE (375 3325);
FORCEPROP 1 LAST COMMENT_BODY TRUE
J 0
(750 3200);
DISPLAY 1.170213 (750 3200);
PAINT GREEN (750 3200);
DISPLAY INVISIBLE (750 3200);
FORCEPROP 2 LAST CDS_LIB mstr_standard
J 0
(650 3275);
PAINT ORANGE (650 3275);
DISPLAY INVISIBLE (650 3275);
FORCEPROP 1 LAST OFFPAGE TRUE
J 0
(975 3150);
DISPLAY 1.170213 (975 3150);
PAINT GREEN (975 3150);
DISPLAY INVISIBLE (975 3150);
FORCEADD RES..2
(-950 3150);
FORCEPROP 1 LAST PACK_TYPE 0402
J 0
(-910 2975);
DISPLAY 0.617021 (-910 2975);
PAINT SKYBLUE (-910 2975);
FORCEPROP 1 LASTPIN (-950 3050) $PN 2
J 0
(-945 3060);
DISPLAY 0.617021 (-945 3060);
PAINT ORANGE (-945 3060);
FORCEPROP 1 LASTPIN (-950 3250) $PN 1
J 0
(-945 3212);
DISPLAY 0.617021 (-945 3212);
PAINT ORANGE (-945 3212);
FORCEPROP 1 LAST TOLERANCE 1%
J 0
(-905 3175);
DISPLAY 0.617021 (-905 3175);
PAINT SKYBLUE (-905 3175);
FORCEPROP 1 LAST LOCATION R8E6
J 0
(-905 3275);
DISPLAY 0.617021 (-905 3275);
PAINT AQUA (-905 3275);
FORCEPROP 1 LAST WATTAGE 1/16W
J 0
(-910 3125);
DISPLAY 0.617021 (-910 3125);
PAINT SKYBLUE (-910 3125);
FORCEPROP 1 LAST VALUE 1.00K
J 0
(-905 3225);
DISPLAY 0.617021 (-905 3225);
PAINT SKYBLUE (-905 3225);
FORCEPROP 1 LAST MATERIAL EMPTY
J 0
(-910 3075);
DISPLAY 0.617021 (-910 3075);
PAINT RED (-910 3075);
FORCEPROP 1 LAST PART_NUMBER G21796-026
J 0
(-910 3025);
DISPLAY 0.617021 (-910 3025);
PAINT BLUE (-910 3025);
FORCEPROP 2 LAST CDS_LIB mstr_discrete
J 0
(-950 3150);
PAINT ORANGE (-950 3150);
DISPLAY INVISIBLE (-950 3150);
FORCEPROP 2 LAST CDS_LOCATION R8E6
J 0
(-905 3275);
DISPLAY 0.617021 (-905 3275);
PAINT AQUA (-905 3275);
DISPLAY INVISIBLE (-905 3275);
FORCEPROP 2 LAST ROOM SB
J 0
(-900 3325);
DISPLAY 1.361702 (-900 3325);
PAINT ORANGE (-900 3325);
DISPLAY INVISIBLE (-900 3325);
FORCEPROP 1 LAST PATH I21
J 0
(-900 3325);
DISPLAY 0.978723 (-900 3325);
PAINT WHITE (-900 3325);
DISPLAY INVISIBLE (-900 3325);
FORCEPROP 2 LAST BOM_COST SB
J 0
(-900 3325);
DISPLAY 1.361702 (-900 3325);
PAINT ORANGE (-900 3325);
DISPLAY INVISIBLE (-900 3325);
FORCEPROP 2 LAST SEC 1
J 0
(-900 3375);
DISPLAY 0.680851 (-900 3375);
PAINT MONO (-900 3375);
DISPLAY INVISIBLE (-900 3375);
FORCEPROP 2 LAST SEC_TYPE 0402
J 0
(-900 3375);
DISPLAY 1.021277 (-900 3375);
PAINT ORANGE (-900 3375);
DISPLAY INVISIBLE (-900 3375);
FORCEADD OFFPAGE..5
(925 1700);
FORCEPROP 2 LAST $XR0 121 
J 0
(670 1700);
DISPLAY 0.638298 (670 1700);
PAINT MONO (670 1700);
FORCEPROP 2 LAST $XR1 154 
J 0
(550 1700);
DISPLAY 0.638298 (550 1700);
PAINT MONO (550 1700);
FORCEPROP 2 LAST PATH I23
J 0
(650 1800);
DISPLAY 1.021277 (650 1800);
PAINT ORANGE (650 1800);
DISPLAY INVISIBLE (650 1800);
FORCEPROP 2 LAST BOM_COST SB
J 0
(650 1750);
DISPLAY 1.361702 (650 1750);
PAINT ORANGE (650 1750);
DISPLAY INVISIBLE (650 1750);
FORCEPROP 2 LAST ROOM SB
J 0
(650 1750);
DISPLAY 1.361702 (650 1750);
PAINT ORANGE (650 1750);
DISPLAY INVISIBLE (650 1750);
FORCEPROP 2 LAST CDS_LIB mstr_standard
J 0
(925 1700);
PAINT ORANGE (925 1700);
DISPLAY INVISIBLE (925 1700);
FORCEPROP 1 LAST COMMENT_BODY TRUE
J 0
(1025 1625);
DISPLAY 1.170213 (1025 1625);
PAINT GREEN (1025 1625);
DISPLAY INVISIBLE (1025 1625);
FORCEPROP 1 LAST OFFPAGE TRUE
J 0
(1250 1575);
DISPLAY 1.170213 (1250 1575);
PAINT GREEN (1250 1575);
DISPLAY INVISIBLE (1250 1575);
FORCEADD RES..2
(-950 2750);
FORCEPROP 1 LASTPIN (-950 2650) $PN 2
J 0
(-945 2660);
DISPLAY 0.617021 (-945 2660);
PAINT WHITE (-945 2660);
FORCEPROP 1 LAST PACK_TYPE 0402
J 0
(-910 2575);
DISPLAY 0.617021 (-910 2575);
PAINT SKYBLUE (-910 2575);
FORCEPROP 1 LAST TOLERANCE 1%
J 0
(-905 2775);
DISPLAY 0.617021 (-905 2775);
PAINT SKYBLUE (-905 2775);
FORCEPROP 1 LASTPIN (-950 2850) $PN 1
J 0
(-945 2812);
DISPLAY 0.617021 (-945 2812);
PAINT WHITE (-945 2812);
FORCEPROP 1 LAST LOCATION R8E4
J 0
(-905 2875);
DISPLAY 0.617021 (-905 2875);
PAINT AQUA (-905 2875);
FORCEPROP 1 LAST WATTAGE 1/16W
J 0
(-910 2725);
DISPLAY 0.617021 (-910 2725);
PAINT SKYBLUE (-910 2725);
FORCEPROP 1 LAST VALUE 1.00K
J 0
(-905 2825);
DISPLAY 0.617021 (-905 2825);
PAINT SKYBLUE (-905 2825);
FORCEPROP 1 LAST PART_NUMBER G21796-026
J 0
(-910 2625);
DISPLAY 0.617021 (-910 2625);
PAINT BLUE (-910 2625);
FORCEPROP 1 LAST MATERIAL EMPTY
J 0
(-910 2675);
DISPLAY 0.617021 (-910 2675);
PAINT RED (-910 2675);
FORCEPROP 2 LAST CDS_LIB mstr_discrete
J 0
(-950 2750);
PAINT ORANGE (-950 2750);
DISPLAY INVISIBLE (-950 2750);
FORCEPROP 2 LAST CDS_LOCATION R8E4
J 0
(-905 2875);
DISPLAY 0.617021 (-905 2875);
PAINT AQUA (-905 2875);
DISPLAY INVISIBLE (-905 2875);
FORCEPROP 2 LAST ROOM SB
J 0
(-900 2925);
DISPLAY 1.361702 (-900 2925);
PAINT ORANGE (-900 2925);
DISPLAY INVISIBLE (-900 2925);
FORCEPROP 1 LAST PATH I24
J 0
(-900 2925);
DISPLAY 0.978723 (-900 2925);
PAINT WHITE (-900 2925);
DISPLAY INVISIBLE (-900 2925);
FORCEPROP 2 LAST BOM_COST SB
J 0
(-900 2925);
DISPLAY 1.361702 (-900 2925);
PAINT ORANGE (-900 2925);
DISPLAY INVISIBLE (-900 2925);
FORCEPROP 2 LAST CDS_SEC 1
J 0
(-900 2975);
DISPLAY 1.361702 (-900 2975);
PAINT ORANGE (-900 2975);
DISPLAY INVISIBLE (-900 2975);
FORCEPROP 2 LAST $SEC 1
J 0
(-900 2975);
DISPLAY 0.914894 (-900 2975);
PAINT MONO (-900 2975);
DISPLAY INVISIBLE (-900 2975);
FORCEADD GND..1
(-950 2500);
FORCEPROP 3 LASTPIN (-950 2550) SIG_NAME GND\g
J 0
(-940 2560);
DISPLAY 0.659574 (-940 2560);
PAINT MONO (-940 2560);
DISPLAY INVISIBLE (-940 2560);
FORCEPROP 1 LAST PATH I25
J 0
(-875 2500);
DISPLAY 0.872340 (-875 2500);
PAINT AQUA (-875 2500);
DISPLAY INVISIBLE (-875 2500);
FORCEPROP 1 LAST BODY_TYPE PLUMBING
J 0
(-995 2457);
DISPLAY 0.340426 (-995 2457);
PAINT GREEN (-995 2457);
DISPLAY INVISIBLE (-995 2457);
FORCEPROP 2 LAST CDS_LIB mstr_symbols
J 0
(-950 2500);
PAINT ORANGE (-950 2500);
DISPLAY INVISIBLE (-950 2500);
FORCEPROP 1 LAST SIZE 1B
J 0
(-875 2450);
DISPLAY 1.170213 (-875 2450);
PAINT AQUA (-875 2450);
DISPLAY INVISIBLE (-875 2450);
FORCEPROP 1 LAST VOLTAGE 0.0V
J 0
(-995 2457);
DISPLAY 0.340426 (-995 2457);
PAINT SKYBLUE (-995 2457);
DISPLAY INVISIBLE (-995 2457);
FORCEPROP 2 LAST BOM_COST SB
J 0
(-925 2575);
DISPLAY 1.361702 (-925 2575);
PAINT ORANGE (-925 2575);
DISPLAY INVISIBLE (-925 2575);
FORCEPROP 2 LAST ROOM SB
J 0
(-925 2575);
DISPLAY 1.361702 (-925 2575);
PAINT ORANGE (-925 2575);
DISPLAY INVISIBLE (-925 2575);
FORCEPROP 1 LAST HDL_POWER GND
J 0
(-950 2650);
DISPLAY 1.170213 (-950 2650);
PAINT GREEN (-950 2650);
DISPLAY INVISIBLE (-950 2650);
FORCEADD RES..2
(-3225 2525);
FORCEPROP 1 LASTPIN (-3225 2425) $PN 2
J 0
(-3220 2435);
DISPLAY 0.617021 (-3220 2435);
PAINT WHITE (-3220 2435);
FORCEPROP 1 LAST TOLERANCE 1%
J 0
(-3180 2550);
DISPLAY 0.617021 (-3180 2550);
PAINT SKYBLUE (-3180 2550);
FORCEPROP 1 LASTPIN (-3225 2625) $PN 1
J 0
(-3220 2587);
DISPLAY 0.617021 (-3220 2587);
PAINT WHITE (-3220 2587);
FORCEPROP 1 LAST WATTAGE 1/16W
J 0
(-3185 2500);
DISPLAY 0.617021 (-3185 2500);
PAINT SKYBLUE (-3185 2500);
FORCEPROP 1 LAST MATERIAL CHIP
J 0
(-3185 2450);
DISPLAY 0.617021 (-3185 2450);
PAINT SKYBLUE (-3185 2450);
FORCEPROP 1 LAST PACK_TYPE 0402
J 0
(-3185 2350);
DISPLAY 0.617021 (-3185 2350);
PAINT SKYBLUE (-3185 2350);
FORCEPROP 1 LAST VALUE 1.00K
J 0
(-3180 2600);
DISPLAY 0.617021 (-3180 2600);
PAINT SKYBLUE (-3180 2600);
FORCEPROP 1 LAST PART_NUMBER G21796-026
J 0
(-3185 2400);
DISPLAY 0.617021 (-3185 2400);
PAINT BLUE (-3185 2400);
FORCEPROP 1 LAST LOCATION R8C18
J 0
(-3180 2650);
DISPLAY 0.617021 (-3180 2650);
PAINT AQUA (-3180 2650);
FORCEPROP 2 LAST CDS_LIB mstr_discrete
J 0
(-3225 2525);
PAINT ORANGE (-3225 2525);
DISPLAY INVISIBLE (-3225 2525);
FORCEPROP 2 LAST ROOM SB
J 0
(-3175 2700);
DISPLAY 1.361702 (-3175 2700);
PAINT ORANGE (-3175 2700);
DISPLAY INVISIBLE (-3175 2700);
FORCEPROP 1 LAST PATH I40
J 0
(-3175 2700);
DISPLAY 0.978723 (-3175 2700);
PAINT WHITE (-3175 2700);
DISPLAY INVISIBLE (-3175 2700);
FORCEPROP 2 LAST CDS_LOCATION R8C18
J 0
(-3180 2650);
DISPLAY 0.617021 (-3180 2650);
PAINT AQUA (-3180 2650);
DISPLAY INVISIBLE (-3180 2650);
FORCEPROP 2 LAST $SEC 1
J 0
(-3175 2750);
DISPLAY 0.914894 (-3175 2750);
PAINT MONO (-3175 2750);
DISPLAY INVISIBLE (-3175 2750);
FORCEPROP 2 LAST BOM_COST SB
J 0
(-3175 2700);
DISPLAY 1.361702 (-3175 2700);
PAINT ORANGE (-3175 2700);
DISPLAY INVISIBLE (-3175 2700);
FORCEPROP 2 LAST CDS_SEC 1
J 0
(-3175 2750);
DISPLAY 1.361702 (-3175 2750);
PAINT ORANGE (-3175 2750);
DISPLAY INVISIBLE (-3175 2750);
FORCEADD RES..2
(-3225 2200);
FORCEPROP 1 LAST PART_NUMBER G21796-026
J 0
(-3160 2025);
DISPLAY 0.617021 (-3160 2025);
PAINT BLUE (-3160 2025);
FORCEPROP 1 LASTPIN (-3225 2300) $PN 1
J 0
(-3220 2262);
DISPLAY 0.617021 (-3220 2262);
PAINT ORANGE (-3220 2262);
FORCEPROP 1 LASTPIN (-3225 2100) $PN 2
J 0
(-3220 2110);
DISPLAY 0.617021 (-3220 2110);
PAINT ORANGE (-3220 2110);
FORCEPROP 1 LAST TOLERANCE 1%
J 0
(-3155 2175);
DISPLAY 0.617021 (-3155 2175);
PAINT SKYBLUE (-3155 2175);
FORCEPROP 1 LAST WATTAGE 1/16W
J 0
(-3160 2125);
DISPLAY 0.617021 (-3160 2125);
PAINT SKYBLUE (-3160 2125);
FORCEPROP 1 LAST VALUE 1.00K
J 0
(-3155 2225);
DISPLAY 0.617021 (-3155 2225);
PAINT SKYBLUE (-3155 2225);
FORCEPROP 1 LAST LOCATION R8C17
J 0
(-3155 2275);
DISPLAY 0.617021 (-3155 2275);
PAINT AQUA (-3155 2275);
FORCEPROP 1 LAST MATERIAL EMPTY
J 0
(-3160 2075);
DISPLAY 0.617021 (-3160 2075);
PAINT RED (-3160 2075);
FORCEPROP 1 LAST PACK_TYPE 0402
J 0
(-3035 2175);
DISPLAY 0.617021 (-3035 2175);
PAINT SKYBLUE (-3035 2175);
FORCEPROP 2 LAST CDS_LIB mstr_discrete
J 0
(-3225 2200);
PAINT ORANGE (-3225 2200);
DISPLAY INVISIBLE (-3225 2200);
FORCEPROP 2 LAST CDS_LOCATION R8C17
J 0
(-3155 2275);
DISPLAY 0.617021 (-3155 2275);
PAINT AQUA (-3155 2275);
DISPLAY INVISIBLE (-3155 2275);
FORCEPROP 2 LAST SEC_TYPE 0402
J 0
(-3175 2425);
DISPLAY 1.021277 (-3175 2425);
PAINT ORANGE (-3175 2425);
DISPLAY INVISIBLE (-3175 2425);
FORCEPROP 2 LAST BOM_COST SB
J 0
(-3175 2375);
DISPLAY 1.361702 (-3175 2375);
PAINT ORANGE (-3175 2375);
DISPLAY INVISIBLE (-3175 2375);
FORCEPROP 2 LAST SEC 1
J 0
(-3175 2425);
DISPLAY 0.914894 (-3175 2425);
PAINT MONO (-3175 2425);
DISPLAY INVISIBLE (-3175 2425);
FORCEPROP 1 LAST PATH I41
J 0
(-3175 2375);
DISPLAY 0.978723 (-3175 2375);
PAINT WHITE (-3175 2375);
DISPLAY INVISIBLE (-3175 2375);
FORCEPROP 2 LAST ROOM SB
J 0
(-3175 2375);
DISPLAY 1.361702 (-3175 2375);
PAINT ORANGE (-3175 2375);
DISPLAY INVISIBLE (-3175 2375);
FORCEADD OFFPAGE..5
(-4225 2350);
FORCEPROP 2 LAST $XR0 119 
J 0
(-4480 2350);
DISPLAY 0.638298 (-4480 2350);
PAINT MONO (-4480 2350);
FORCEPROP 2 LAST PATH I43
J 0
(-4525 2400);
DISPLAY 1.021277 (-4525 2400);
PAINT ORANGE (-4525 2400);
DISPLAY INVISIBLE (-4525 2400);
FORCEPROP 2 LAST ROOM SB
J 0
(-4500 2400);
DISPLAY 1.361702 (-4500 2400);
PAINT ORANGE (-4500 2400);
DISPLAY INVISIBLE (-4500 2400);
FORCEPROP 2 LAST BOM_COST SB
J 0
(-4500 2400);
DISPLAY 1.361702 (-4500 2400);
PAINT ORANGE (-4500 2400);
DISPLAY INVISIBLE (-4500 2400);
FORCEPROP 1 LAST COMMENT_BODY TRUE
J 0
(-4125 2275);
DISPLAY 1.170213 (-4125 2275);
PAINT GREEN (-4125 2275);
DISPLAY INVISIBLE (-4125 2275);
FORCEPROP 2 LAST CDS_LIB mstr_standard
J 0
(-4225 2350);
PAINT ORANGE (-4225 2350);
DISPLAY INVISIBLE (-4225 2350);
FORCEPROP 1 LAST OFFPAGE TRUE
J 0
(-3900 2225);
DISPLAY 1.170213 (-3900 2225);
PAINT GREEN (-3900 2225);
DISPLAY INVISIBLE (-3900 2225);
FORCEADD P3V3_STBY..1
(-950 3375);
FORCEPROP 3 LASTPIN (-950 3325) SIG_NAME P3V3_STBY\g
J 0
(-940 3335);
DISPLAY 0.659574 (-940 3335);
PAINT MONO (-940 3335);
DISPLAY INVISIBLE (-940 3335);
FORCEPROP 1 LAST HDL_POWER P3V3_STBY
J 0
(-1250 3250);
DISPLAY 0.872340 (-1250 3250);
PAINT ORANGE (-1250 3250);
DISPLAY INVISIBLE (-1250 3250);
FORCEPROP 1 LAST PATH I48
J 0
(-905 3377);
DISPLAY 0.340426 (-905 3377);
PAINT GREEN (-905 3377);
DISPLAY INVISIBLE (-905 3377);
FORCEPROP 1 LAST BODY_TYPE PLUMBING
J 0
(-995 3332);
DISPLAY 0.340426 (-995 3332);
PAINT GREEN (-995 3332);
DISPLAY INVISIBLE (-995 3332);
FORCEPROP 1 LAST SIZE 1B
J 0
(-905 3397);
DISPLAY 0.340426 (-905 3397);
PAINT GREEN (-905 3397);
DISPLAY INVISIBLE (-905 3397);
FORCEPROP 2 LAST CDS_LIB mstr_symbols
J 0
(-950 3375);
PAINT ORANGE (-950 3375);
DISPLAY INVISIBLE (-950 3375);
FORCEPROP 1 LAST VOLTAGE 3.3V
J 0
(-995 3332);
DISPLAY 0.340426 (-995 3332);
PAINT SKYBLUE (-995 3332);
DISPLAY INVISIBLE (-995 3332);
FORCEADD P3V3_STBY..1
(-3225 2750);
FORCEPROP 3 LASTPIN (-3225 2700) SIG_NAME P3V3_STBY\g
J 0
(-3215 2710);
DISPLAY 0.659574 (-3215 2710);
PAINT MONO (-3215 2710);
DISPLAY INVISIBLE (-3215 2710);
FORCEPROP 1 LAST HDL_POWER P3V3_STBY
J 0
(-3525 2625);
DISPLAY 0.872340 (-3525 2625);
PAINT ORANGE (-3525 2625);
DISPLAY INVISIBLE (-3525 2625);
FORCEPROP 1 LAST VOLTAGE 3.3V
J 0
(-3270 2707);
DISPLAY 0.340426 (-3270 2707);
PAINT SKYBLUE (-3270 2707);
DISPLAY INVISIBLE (-3270 2707);
FORCEPROP 2 LAST CDS_LIB mstr_symbols
J 0
(-3225 2750);
PAINT ORANGE (-3225 2750);
DISPLAY INVISIBLE (-3225 2750);
FORCEPROP 1 LAST BODY_TYPE PLUMBING
J 0
(-3270 2707);
DISPLAY 0.340426 (-3270 2707);
PAINT GREEN (-3270 2707);
DISPLAY INVISIBLE (-3270 2707);
FORCEPROP 1 LAST SIZE 1B
J 0
(-3180 2772);
DISPLAY 0.340426 (-3180 2772);
PAINT GREEN (-3180 2772);
DISPLAY INVISIBLE (-3180 2772);
FORCEPROP 1 LAST PATH I49
J 0
(-3180 2752);
DISPLAY 0.340426 (-3180 2752);
PAINT GREEN (-3180 2752);
DISPLAY INVISIBLE (-3180 2752);
FORCEADD RES..2
(-925 4450);
FORCEPROP 1 LAST PACK_TYPE 0402
J 0
(-885 4275);
DISPLAY 0.617021 (-885 4275);
PAINT SKYBLUE (-885 4275);
FORCEPROP 1 LASTPIN (-925 4550) $PN 1
J 0
(-920 4512);
DISPLAY 0.617021 (-920 4512);
PAINT WHITE (-920 4512);
FORCEPROP 1 LASTPIN (-925 4350) $PN 2
J 0
(-920 4360);
DISPLAY 0.617021 (-920 4360);
PAINT WHITE (-920 4360);
FORCEPROP 1 LAST TOLERANCE 1%
J 0
(-880 4475);
DISPLAY 0.617021 (-880 4475);
PAINT SKYBLUE (-880 4475);
FORCEPROP 1 LAST WATTAGE 1/16W
J 0
(-885 4425);
DISPLAY 0.617021 (-885 4425);
PAINT SKYBLUE (-885 4425);
FORCEPROP 1 LAST VALUE 1.00K
J 0
(-880 4525);
DISPLAY 0.617021 (-880 4525);
PAINT SKYBLUE (-880 4525);
FORCEPROP 1 LAST PART_NUMBER G21796-026
J 0
(-885 4325);
DISPLAY 0.617021 (-885 4325);
PAINT BLUE (-885 4325);
FORCEPROP 1 LAST LOCATION R8D5
J 0
(-880 4575);
DISPLAY 0.617021 (-880 4575);
PAINT AQUA (-880 4575);
FORCEPROP 1 LAST MATERIAL EMPTY
J 0
(-885 4375);
DISPLAY 0.617021 (-885 4375);
PAINT RED (-885 4375);
FORCEPROP 2 LAST CDS_LIB mstr_discrete
J 0
(-925 4450);
PAINT ORANGE (-925 4450);
DISPLAY INVISIBLE (-925 4450);
FORCEPROP 2 LAST CDS_LOCATION R8D5
J 0
(-880 4575);
DISPLAY 0.617021 (-880 4575);
PAINT AQUA (-880 4575);
DISPLAY INVISIBLE (-880 4575);
FORCEPROP 2 LAST BOM_COST SB
J 0
(-875 4625);
DISPLAY 1.361702 (-875 4625);
PAINT ORANGE (-875 4625);
DISPLAY INVISIBLE (-875 4625);
FORCEPROP 2 LAST CDS_SEC 1
J 0
(-875 4675);
DISPLAY 1.361702 (-875 4675);
PAINT ORANGE (-875 4675);
DISPLAY INVISIBLE (-875 4675);
FORCEPROP 2 LAST $SEC 1
J 0
(-875 4675);
DISPLAY 0.914894 (-875 4675);
PAINT MONO (-875 4675);
DISPLAY INVISIBLE (-875 4675);
FORCEPROP 1 LAST PATH I50
J 0
(-875 4625);
DISPLAY 0.978723 (-875 4625);
PAINT WHITE (-875 4625);
DISPLAY INVISIBLE (-875 4625);
FORCEPROP 2 LAST ROOM SB
J 0
(-875 4625);
DISPLAY 1.361702 (-875 4625);
PAINT ORANGE (-875 4625);
DISPLAY INVISIBLE (-875 4625);
FORCEADD P3V3_STBY..1
(-925 5100);
FORCEPROP 3 LASTPIN (-925 5050) SIG_NAME P3V3_STBY\g
J 0
(-915 5060);
DISPLAY 0.659574 (-915 5060);
PAINT MONO (-915 5060);
DISPLAY INVISIBLE (-915 5060);
FORCEPROP 1 LAST HDL_POWER P3V3_STBY
J 0
(-1225 4975);
DISPLAY 0.872340 (-1225 4975);
PAINT ORANGE (-1225 4975);
DISPLAY INVISIBLE (-1225 4975);
FORCEPROP 1 LAST BODY_TYPE PLUMBING
J 0
(-970 5057);
DISPLAY 0.340426 (-970 5057);
PAINT GREEN (-970 5057);
DISPLAY INVISIBLE (-970 5057);
FORCEPROP 1 LAST VOLTAGE 3.3V
J 0
(-970 5057);
DISPLAY 0.340426 (-970 5057);
PAINT SKYBLUE (-970 5057);
DISPLAY INVISIBLE (-970 5057);
FORCEPROP 1 LAST PATH I51
J 0
(-880 5102);
DISPLAY 0.340426 (-880 5102);
PAINT GREEN (-880 5102);
DISPLAY INVISIBLE (-880 5102);
FORCEPROP 2 LAST CDS_LIB mstr_symbols
J 0
(-925 5100);
PAINT ORANGE (-925 5100);
DISPLAY INVISIBLE (-925 5100);
FORCEPROP 1 LAST SIZE 1B
J 0
(-880 5122);
DISPLAY 0.340426 (-880 5122);
PAINT GREEN (-880 5122);
DISPLAY INVISIBLE (-880 5122);
FORCEADD RES..2
(-925 4925);
FORCEPROP 1 LASTPIN (-925 4825) $PN 2
J 0
(-920 4835);
DISPLAY 0.617021 (-920 4835);
PAINT WHITE (-920 4835);
FORCEPROP 1 LASTPIN (-925 5025) $PN 1
J 0
(-920 4987);
DISPLAY 0.617021 (-920 4987);
PAINT WHITE (-920 4987);
FORCEPROP 1 LAST TOLERANCE 1%
J 0
(-850 4925);
DISPLAY 0.617021 (-850 4925);
PAINT SKYBLUE (-850 4925);
FORCEPROP 1 LAST WATTAGE 1/16W
J 0
(-850 4875);
DISPLAY 0.617021 (-850 4875);
PAINT SKYBLUE (-850 4875);
FORCEPROP 1 LAST MATERIAL CHIP
J 0
(-850 4825);
DISPLAY 0.617021 (-850 4825);
PAINT SKYBLUE (-850 4825);
FORCEPROP 1 LAST PACK_TYPE 0402
J 0
(-850 4725);
DISPLAY 0.617021 (-850 4725);
PAINT SKYBLUE (-850 4725);
FORCEPROP 1 LAST VALUE 10.0K
J 0
(-850 4975);
DISPLAY 0.617021 (-850 4975);
PAINT SKYBLUE (-850 4975);
FORCEPROP 1 LAST PART_NUMBER G21796-016
J 0
(-850 4775);
DISPLAY 0.617021 (-850 4775);
PAINT BLUE (-850 4775);
FORCEPROP 1 LAST LOCATION R8D13
J 0
(-850 5025);
DISPLAY 0.617021 (-850 5025);
PAINT AQUA (-850 5025);
FORCEPROP 2 LAST CDS_LIB mstr_discrete
J 0
(-925 4925);
PAINT ORANGE (-925 4925);
DISPLAY INVISIBLE (-925 4925);
FORCEPROP 2 LAST CDS_LOCATION R8D13
J 0
(-850 5025);
DISPLAY 0.617021 (-850 5025);
PAINT AQUA (-850 5025);
DISPLAY INVISIBLE (-850 5025);
FORCEPROP 2 LAST ROOM SB_HEADERS
R 3
J 0
(-725 5000);
PAINT ORANGE (-725 5000);
DISPLAY INVISIBLE (-725 5000);
FORCEPROP 2 LAST BOM_COST SB
R 3
J 0
(-725 5000);
PAINT ORANGE (-725 5000);
DISPLAY INVISIBLE (-725 5000);
FORCEPROP 1 LAST PATH I52
J 0
(-875 5100);
DISPLAY 0.978723 (-875 5100);
PAINT WHITE (-875 5100);
DISPLAY INVISIBLE (-875 5100);
FORCEPROP 2 LAST $SEC 1
J 0
(-875 5150);
DISPLAY 0.914894 (-875 5150);
PAINT MONO (-875 5150);
DISPLAY INVISIBLE (-875 5150);
FORCEPROP 2 LAST CDS_SEC 1
J 0
(-875 5150);
DISPLAY 1.361702 (-875 5150);
PAINT ORANGE (-875 5150);
DISPLAY INVISIBLE (-875 5150);
FORCEADD OFFPAGE..5
(-1800 4675);
FORCEPROP 2 LAST $XR0 120 
J 0
(-2055 4675);
DISPLAY 0.638298 (-2055 4675);
PAINT MONO (-2055 4675);
FORCEPROP 2 LAST BOM_COST SB
J 0
(-2075 4725);
DISPLAY 1.361702 (-2075 4725);
PAINT ORANGE (-2075 4725);
DISPLAY INVISIBLE (-2075 4725);
FORCEPROP 2 LAST ROOM SB
J 0
(-2075 4725);
DISPLAY 1.361702 (-2075 4725);
PAINT ORANGE (-2075 4725);
DISPLAY INVISIBLE (-2075 4725);
FORCEPROP 1 LAST COMMENT_BODY TRUE
J 0
(-1700 4600);
DISPLAY 1.170213 (-1700 4600);
PAINT GREEN (-1700 4600);
DISPLAY INVISIBLE (-1700 4600);
FORCEPROP 2 LAST PATH I53
J 0
(-2045 4720);
DISPLAY 1.021277 (-2045 4720);
PAINT ORANGE (-2045 4720);
DISPLAY INVISIBLE (-2045 4720);
FORCEPROP 2 LAST CDS_LIB mstr_standard
J 0
(-1800 4675);
PAINT ORANGE (-1800 4675);
DISPLAY INVISIBLE (-1800 4675);
FORCEPROP 1 LAST OFFPAGE TRUE
J 0
(-1475 4550);
DISPLAY 1.170213 (-1475 4550);
PAINT GREEN (-1475 4550);
DISPLAY INVISIBLE (-1475 4550);
FORCEADD GND..1
(-925 4200);
FORCEPROP 3 LASTPIN (-925 4250) SIG_NAME GND\g
J 0
(-915 4260);
DISPLAY 0.659574 (-915 4260);
PAINT MONO (-915 4260);
DISPLAY INVISIBLE (-915 4260);
FORCEPROP 1 LAST VOLTAGE 0.0V
J 0
(-970 4157);
DISPLAY 0.340426 (-970 4157);
PAINT SKYBLUE (-970 4157);
DISPLAY INVISIBLE (-970 4157);
FORCEPROP 1 LAST BODY_TYPE PLUMBING
J 0
(-970 4157);
DISPLAY 0.340426 (-970 4157);
PAINT GREEN (-970 4157);
DISPLAY INVISIBLE (-970 4157);
FORCEPROP 2 LAST CDS_LIB mstr_symbols
J 0
(-925 4200);
PAINT ORANGE (-925 4200);
DISPLAY INVISIBLE (-925 4200);
FORCEPROP 2 LAST BOM_COST SB
J 0
(-900 4275);
DISPLAY 1.361702 (-900 4275);
PAINT ORANGE (-900 4275);
DISPLAY INVISIBLE (-900 4275);
FORCEPROP 2 LAST ROOM SB
J 0
(-900 4275);
DISPLAY 1.361702 (-900 4275);
PAINT ORANGE (-900 4275);
DISPLAY INVISIBLE (-900 4275);
FORCEPROP 1 LAST PATH I54
J 0
(-850 4200);
DISPLAY 0.872340 (-850 4200);
PAINT AQUA (-850 4200);
DISPLAY INVISIBLE (-850 4200);
FORCEPROP 1 LAST SIZE 1B
J 0
(-850 4150);
DISPLAY 1.170213 (-850 4150);
PAINT AQUA (-850 4150);
DISPLAY INVISIBLE (-850 4150);
FORCEPROP 1 LAST HDL_POWER GND
J 0
(-925 4350);
DISPLAY 1.170213 (-925 4350);
PAINT GREEN (-925 4350);
DISPLAY INVISIBLE (-925 4350);
FORCEADD GND..1
(-3225 2000);
FORCEPROP 3 LASTPIN (-3225 2050) SIG_NAME GND\g
J 0
(-3215 2060);
DISPLAY 0.659574 (-3215 2060);
PAINT MONO (-3215 2060);
DISPLAY INVISIBLE (-3215 2060);
FORCEPROP 1 LAST PATH I6
J 0
(-3150 2000);
DISPLAY 0.872340 (-3150 2000);
PAINT AQUA (-3150 2000);
DISPLAY INVISIBLE (-3150 2000);
FORCEPROP 1 LAST BODY_TYPE PLUMBING
J 0
(-3270 1957);
DISPLAY 0.340426 (-3270 1957);
PAINT GREEN (-3270 1957);
DISPLAY INVISIBLE (-3270 1957);
FORCEPROP 1 LAST SIZE 1B
J 0
(-3150 1950);
DISPLAY 1.170213 (-3150 1950);
PAINT AQUA (-3150 1950);
DISPLAY INVISIBLE (-3150 1950);
FORCEPROP 2 LAST CDS_LIB mstr_symbols
J 0
(-3225 2000);
PAINT ORANGE (-3225 2000);
DISPLAY INVISIBLE (-3225 2000);
FORCEPROP 1 LAST VOLTAGE 0.0V
J 0
(-3270 1957);
DISPLAY 0.340426 (-3270 1957);
PAINT SKYBLUE (-3270 1957);
DISPLAY INVISIBLE (-3270 1957);
FORCEPROP 1 LAST HDL_POWER GND
J 0
(-3225 2150);
DISPLAY 1.170213 (-3225 2150);
PAINT GREEN (-3225 2150);
DISPLAY INVISIBLE (-3225 2150);
FORCEPROP 2 LAST ROOM SB
J 0
(-3200 2075);
DISPLAY 1.361702 (-3200 2075);
PAINT ORANGE (-3200 2075);
DISPLAY INVISIBLE (-3200 2075);
FORCEPROP 2 LAST BOM_COST SB
J 0
(-3200 2075);
DISPLAY 1.361702 (-3200 2075);
PAINT ORANGE (-3200 2075);
DISPLAY INVISIBLE (-3200 2075);
FORCEADD RES..2
(-3275 4975);
FORCEPROP 1 LAST PACK_TYPE 0402
J 0
(-3235 4800);
DISPLAY 0.617021 (-3235 4800);
PAINT SKYBLUE (-3235 4800);
FORCEPROP 1 LAST WATTAGE 1/16W
J 0
(-3235 4950);
DISPLAY 0.617021 (-3235 4950);
PAINT SKYBLUE (-3235 4950);
FORCEPROP 1 LAST TOLERANCE 1%
J 0
(-3230 5000);
DISPLAY 0.617021 (-3230 5000);
PAINT SKYBLUE (-3230 5000);
FORCEPROP 1 LAST VALUE 8.2K
J 0
(-3230 5050);
DISPLAY 0.617021 (-3230 5050);
PAINT SKYBLUE (-3230 5050);
FORCEPROP 1 LAST MATERIAL EMPTY
J 0
(-3235 4900);
DISPLAY 0.617021 (-3235 4900);
PAINT RED (-3235 4900);
FORCEPROP 1 LAST LOCATION R7D13
J 0
(-3230 5100);
DISPLAY 0.617021 (-3230 5100);
PAINT AQUA (-3230 5100);
FORCEPROP 1 LAST PART_NUMBER G21796-345
J 0
(-3235 4850);
DISPLAY 0.617021 (-3235 4850);
PAINT BLUE (-3235 4850);
FORCEPROP 1 LASTPIN (-3275 4875) $PN 2
J 0
(-3270 4885);
DISPLAY 0.787234 (-3270 4885);
PAINT ORANGE (-3270 4885);
DISPLAY INVISIBLE (-3270 4885);
FORCEPROP 2 LAST CDS_LIB mstr_discrete
J 0
(-3275 4975);
PAINT ORANGE (-3275 4975);
DISPLAY INVISIBLE (-3275 4975);
FORCEPROP 1 LASTPIN (-3275 5075) $PN 1
J 0
(-3270 5037);
DISPLAY 0.787234 (-3270 5037);
PAINT ORANGE (-3270 5037);
DISPLAY INVISIBLE (-3270 5037);
FORCEPROP 2 LAST CDS_LOCATION R7D13
J 0
(-3230 5100);
DISPLAY 0.617021 (-3230 5100);
PAINT AQUA (-3230 5100);
DISPLAY INVISIBLE (-3230 5100);
FORCEPROP 2 LAST BOM_COST SB
J 0
(-3225 5150);
DISPLAY 1.361702 (-3225 5150);
PAINT ORANGE (-3225 5150);
DISPLAY INVISIBLE (-3225 5150);
FORCEPROP 2 LAST CDS_SEC 1
J 0
(-3225 5200);
DISPLAY 1.361702 (-3225 5200);
PAINT ORANGE (-3225 5200);
DISPLAY INVISIBLE (-3225 5200);
FORCEPROP 2 LAST $SEC 1
J 0
(-3225 5200);
PAINT MONO (-3225 5200);
DISPLAY INVISIBLE (-3225 5200);
FORCEPROP 1 LAST PATH I60
J 0
(-3225 5150);
DISPLAY 0.978723 (-3225 5150);
PAINT WHITE (-3225 5150);
DISPLAY INVISIBLE (-3225 5150);
FORCEPROP 2 LAST ROOM SB
J 0
(-3225 5150);
DISPLAY 1.361702 (-3225 5150);
PAINT ORANGE (-3225 5150);
DISPLAY INVISIBLE (-3225 5150);
FORCEADD P3V3_STBY..1
(-3275 5200);
FORCEPROP 3 LASTPIN (-3275 5150) SIG_NAME P3V3_STBY\g
J 0
(-3265 5160);
DISPLAY 0.659574 (-3265 5160);
PAINT MONO (-3265 5160);
DISPLAY INVISIBLE (-3265 5160);
FORCEPROP 1 LAST HDL_POWER P3V3_STBY
J 0
(-3575 5075);
DISPLAY 0.872340 (-3575 5075);
PAINT ORANGE (-3575 5075);
DISPLAY INVISIBLE (-3575 5075);
FORCEPROP 1 LAST VOLTAGE 3.3V
J 0
(-3320 5157);
DISPLAY 0.340426 (-3320 5157);
PAINT SKYBLUE (-3320 5157);
DISPLAY INVISIBLE (-3320 5157);
FORCEPROP 1 LAST SIZE 1B
J 0
(-3230 5222);
DISPLAY 0.340426 (-3230 5222);
PAINT GREEN (-3230 5222);
DISPLAY INVISIBLE (-3230 5222);
FORCEPROP 2 LAST CDS_LIB mstr_symbols
J 0
(-3275 5200);
PAINT ORANGE (-3275 5200);
DISPLAY INVISIBLE (-3275 5200);
FORCEPROP 1 LAST BODY_TYPE PLUMBING
J 0
(-3320 5157);
DISPLAY 0.340426 (-3320 5157);
PAINT GREEN (-3320 5157);
DISPLAY INVISIBLE (-3320 5157);
FORCEPROP 1 LAST PATH I61
J 0
(-3230 5202);
DISPLAY 0.340426 (-3230 5202);
PAINT GREEN (-3230 5202);
DISPLAY INVISIBLE (-3230 5202);
FORCEADD OFFPAGE..6
(-4075 4800);
FORCEPROP 2 LAST $XR0 121 
J 0
(-4355 4800);
DISPLAY 0.638298 (-4355 4800);
PAINT MONO (-4355 4800);
FORCEPROP 2 LAST $XR1 147 
J 0
(-4475 4800);
DISPLAY 0.638298 (-4475 4800);
PAINT MONO (-4475 4800);
FORCEPROP 2 LAST PATH I64
J 0
(-4350 4850);
DISPLAY 1.021277 (-4350 4850);
PAINT ORANGE (-4350 4850);
DISPLAY INVISIBLE (-4350 4850);
FORCEPROP 1 LAST COMMENT_BODY TRUE
J 0
(-3975 4725);
DISPLAY 1.170213 (-3975 4725);
PAINT GREEN (-3975 4725);
DISPLAY INVISIBLE (-3975 4725);
FORCEPROP 1 LAST OFFPAGE TRUE
J 0
(-3750 4675);
DISPLAY 1.170213 (-3750 4675);
PAINT GREEN (-3750 4675);
DISPLAY INVISIBLE (-3750 4675);
FORCEPROP 2 LAST CDS_LIB mstr_standard
J 0
(-4075 4800);
PAINT ORANGE (-4075 4800);
DISPLAY INVISIBLE (-4075 4800);
FORCEADD OFFPAGE..2
(-3850 3575);
FORCEPROP 2 LAST $XR0 121 
J 0
(-3661 3575);
DISPLAY 0.638298 (-3661 3575);
PAINT MONO (-3661 3575);
FORCEPROP 2 LAST $XR1 139 
J 0
(-3541 3575);
DISPLAY 0.638298 (-3541 3575);
PAINT MONO (-3541 3575);
FORCEPROP 1 LAST COMMENT_BODY TRUE
J 0
(-3895 3480);
DISPLAY 1.170213 (-3895 3480);
PAINT GREEN (-3895 3480);
DISPLAY INVISIBLE (-3895 3480);
FORCEPROP 2 LAST CDS_LIB mstr_standard
J 0
(-3850 3575);
PAINT MONO (-3850 3575);
DISPLAY INVISIBLE (-3850 3575);
FORCEPROP 2 LAST PATH I65
J 0
(-3675 3650);
DISPLAY 1.021277 (-3675 3650);
PAINT ORANGE (-3675 3650);
DISPLAY INVISIBLE (-3675 3650);
FORCEPROP 1 LAST OFFPAGE TRUE
J 0
(-3525 3450);
DISPLAY 1.170213 (-3525 3450);
PAINT GREEN (-3525 3450);
DISPLAY INVISIBLE (-3525 3450);
FORCEADD P3V3_STBY..1
(-5050 3975);
FORCEPROP 3 LASTPIN (-5050 3925) SIG_NAME P3V3_STBY\g
J 0
(-5040 3935);
DISPLAY 0.659574 (-5040 3935);
PAINT MONO (-5040 3935);
DISPLAY INVISIBLE (-5040 3935);
FORCEPROP 1 LAST HDL_POWER P3V3_STBY
J 0
(-5350 3850);
DISPLAY 0.872340 (-5350 3850);
PAINT ORANGE (-5350 3850);
DISPLAY INVISIBLE (-5350 3850);
FORCEPROP 1 LAST BODY_TYPE PLUMBING
J 0
(-5095 3932);
DISPLAY 0.340426 (-5095 3932);
PAINT GREEN (-5095 3932);
DISPLAY INVISIBLE (-5095 3932);
FORCEPROP 1 LAST VOLTAGE 3.3V
J 0
(-5095 3932);
DISPLAY 0.340426 (-5095 3932);
PAINT SKYBLUE (-5095 3932);
DISPLAY INVISIBLE (-5095 3932);
FORCEPROP 1 LAST PATH I66
J 0
(-5005 3977);
DISPLAY 0.340426 (-5005 3977);
PAINT GREEN (-5005 3977);
DISPLAY INVISIBLE (-5005 3977);
FORCEPROP 1 LAST SIZE 1B
J 0
(-5005 3997);
DISPLAY 0.340426 (-5005 3997);
PAINT GREEN (-5005 3997);
DISPLAY INVISIBLE (-5005 3997);
FORCEPROP 2 LAST CDS_LIB mstr_symbols
J 0
(-5050 3975);
PAINT MONO (-5050 3975);
DISPLAY INVISIBLE (-5050 3975);
FORCEADD GND..1
(-5050 3175);
FORCEPROP 3 LASTPIN (-5050 3225) SIG_NAME GND\g
J 0
(-5040 3235);
DISPLAY 0.659574 (-5040 3235);
PAINT MONO (-5040 3235);
DISPLAY INVISIBLE (-5040 3235);
FORCEPROP 1 LAST VOLTAGE 0.0V
J 0
(-5095 3132);
DISPLAY 0.340426 (-5095 3132);
PAINT SKYBLUE (-5095 3132);
DISPLAY INVISIBLE (-5095 3132);
FORCEPROP 1 LAST BODY_TYPE PLUMBING
J 0
(-5095 3132);
DISPLAY 0.340426 (-5095 3132);
PAINT GREEN (-5095 3132);
DISPLAY INVISIBLE (-5095 3132);
FORCEPROP 2 LAST CDS_LIB mstr_symbols
J 0
(-5050 3175);
PAINT MONO (-5050 3175);
DISPLAY INVISIBLE (-5050 3175);
FORCEPROP 2 LAST BOM_COST SB
J 0
(-5025 3250);
DISPLAY 1.361702 (-5025 3250);
PAINT ORANGE (-5025 3250);
DISPLAY INVISIBLE (-5025 3250);
FORCEPROP 2 LAST ROOM SB
J 0
(-5025 3250);
DISPLAY 1.361702 (-5025 3250);
PAINT ORANGE (-5025 3250);
DISPLAY INVISIBLE (-5025 3250);
FORCEPROP 1 LAST SIZE 1B
J 0
(-4975 3125);
DISPLAY 1.170213 (-4975 3125);
PAINT AQUA (-4975 3125);
DISPLAY INVISIBLE (-4975 3125);
FORCEPROP 1 LAST PATH I69
J 0
(-4975 3175);
DISPLAY 0.872340 (-4975 3175);
PAINT AQUA (-4975 3175);
DISPLAY INVISIBLE (-4975 3175);
FORCEPROP 1 LAST HDL_POWER GND
J 0
(-5050 3325);
DISPLAY 1.170213 (-5050 3325);
PAINT GREEN (-5050 3325);
DISPLAY INVISIBLE (-5050 3325);
FORCEADD OFFPAGE..5
(-1450 2975);
FORCEPROP 2 LAST $XR0 111 
J 0
(-1705 2975);
DISPLAY 0.638298 (-1705 2975);
PAINT MONO (-1705 2975);
FORCEPROP 2 LAST $XR1 121 
J 0
(-1825 2975);
DISPLAY 0.638298 (-1825 2975);
PAINT MONO (-1825 2975);
FORCEPROP 2 LAST $XR2 154 
J 0
(-1945 2975);
DISPLAY 0.638298 (-1945 2975);
PAINT MONO (-1945 2975);
FORCEPROP 2 LAST $XR3 184 
J 0
(-2065 2975);
DISPLAY 0.638298 (-2065 2975);
PAINT MONO (-2065 2975);
FORCEPROP 2 LAST PATH I7
J 0
(-1725 3025);
DISPLAY 1.021277 (-1725 3025);
PAINT ORANGE (-1725 3025);
DISPLAY INVISIBLE (-1725 3025);
FORCEPROP 1 LAST COMMENT_BODY TRUE
J 0
(-1350 2900);
DISPLAY 1.170213 (-1350 2900);
PAINT GREEN (-1350 2900);
DISPLAY INVISIBLE (-1350 2900);
FORCEPROP 2 LAST CDS_LIB mstr_standard
J 0
(-1450 2975);
PAINT ORANGE (-1450 2975);
DISPLAY INVISIBLE (-1450 2975);
FORCEPROP 1 LAST OFFPAGE TRUE
J 0
(-1125 2850);
DISPLAY 1.170213 (-1125 2850);
PAINT GREEN (-1125 2850);
DISPLAY INVISIBLE (-1125 2850);
FORCEPROP 2 LAST BOM_COST SB
J 0
(-1725 3025);
DISPLAY 1.361702 (-1725 3025);
PAINT ORANGE (-1725 3025);
DISPLAY INVISIBLE (-1725 3025);
FORCEPROP 2 LAST ROOM SB
J 0
(-1725 3025);
DISPLAY 1.361702 (-1725 3025);
PAINT ORANGE (-1725 3025);
DISPLAY INVISIBLE (-1725 3025);
FORCEADD RES..2
(-5050 3375);
FORCEPROP 1 LASTPIN (-5050 3275) $PN 2
J 0
(-5045 3285);
DISPLAY 0.617021 (-5045 3285);
PAINT ORANGE (-5045 3285);
FORCEPROP 1 LAST PACK_TYPE 0402
J 0
(-5010 3200);
DISPLAY 0.617021 (-5010 3200);
PAINT SKYBLUE (-5010 3200);
FORCEPROP 1 LAST MATERIAL CHIP
J 0
(-5010 3300);
DISPLAY 0.617021 (-5010 3300);
PAINT SKYBLUE (-5010 3300);
FORCEPROP 1 LASTPIN (-5050 3475) $PN 1
J 0
(-5045 3437);
DISPLAY 0.617021 (-5045 3437);
PAINT ORANGE (-5045 3437);
FORCEPROP 1 LAST LOCATION R7D1
J 0
(-5005 3500);
DISPLAY 0.617021 (-5005 3500);
PAINT AQUA (-5005 3500);
FORCEPROP 1 LAST TOLERANCE 1%
J 0
(-5005 3400);
DISPLAY 0.617021 (-5005 3400);
PAINT SKYBLUE (-5005 3400);
FORCEPROP 1 LAST WATTAGE 1/16W
J 0
(-5010 3350);
DISPLAY 0.617021 (-5010 3350);
PAINT SKYBLUE (-5010 3350);
FORCEPROP 1 LAST VALUE 1.00K
J 0
(-5005 3450);
DISPLAY 0.617021 (-5005 3450);
PAINT SKYBLUE (-5005 3450);
FORCEPROP 1 LAST PART_NUMBER G21796-026
J 0
(-5010 3250);
DISPLAY 0.617021 (-5010 3250);
PAINT BLUE (-5010 3250);
FORCEPROP 2 LAST CDS_LIB mstr_discrete
J 0
(-5050 3375);
PAINT MONO (-5050 3375);
DISPLAY INVISIBLE (-5050 3375);
FORCEPROP 2 LAST CDS_LOCATION R7D1
J 0
(-5005 3500);
DISPLAY 0.617021 (-5005 3500);
PAINT AQUA (-5005 3500);
DISPLAY INVISIBLE (-5005 3500);
FORCEPROP 2 LAST ROOM SB
J 0
(-5000 3550);
DISPLAY 1.361702 (-5000 3550);
PAINT ORANGE (-5000 3550);
DISPLAY INVISIBLE (-5000 3550);
FORCEPROP 1 LAST PATH I70
J 0
(-5000 3550);
DISPLAY 0.978723 (-5000 3550);
PAINT WHITE (-5000 3550);
DISPLAY INVISIBLE (-5000 3550);
FORCEPROP 2 LAST BOM_COST SB
J 0
(-5000 3550);
DISPLAY 1.361702 (-5000 3550);
PAINT ORANGE (-5000 3550);
DISPLAY INVISIBLE (-5000 3550);
FORCEPROP 2 LAST SEC_TYPE 0402
J 0
(-5000 3600);
DISPLAY 1.021277 (-5000 3600);
PAINT ORANGE (-5000 3600);
DISPLAY INVISIBLE (-5000 3600);
FORCEPROP 2 LAST SEC 1
J 0
(-5000 3600);
DISPLAY 0.680851 (-5000 3600);
PAINT MONO (-5000 3600);
DISPLAY INVISIBLE (-5000 3600);
FORCEADD RES..2
(-5050 3750);
FORCEPROP 1 LAST PACK_TYPE 0402
J 0
(-5010 3575);
DISPLAY 0.617021 (-5010 3575);
PAINT SKYBLUE (-5010 3575);
FORCEPROP 1 LASTPIN (-5050 3650) $PN 2
J 0
(-5045 3660);
DISPLAY 0.617021 (-5045 3660);
PAINT ORANGE (-5045 3660);
FORCEPROP 1 LASTPIN (-5050 3850) $PN 1
J 0
(-5045 3812);
DISPLAY 0.617021 (-5045 3812);
PAINT ORANGE (-5045 3812);
FORCEPROP 1 LAST WATTAGE 1/16W
J 0
(-5010 3725);
DISPLAY 0.617021 (-5010 3725);
PAINT SKYBLUE (-5010 3725);
FORCEPROP 1 LAST TOLERANCE 1%
J 0
(-5005 3775);
DISPLAY 0.617021 (-5005 3775);
PAINT SKYBLUE (-5005 3775);
FORCEPROP 1 LAST MATERIAL EMPTY
J 0
(-5010 3675);
DISPLAY 0.617021 (-5010 3675);
PAINT RED (-5010 3675);
FORCEPROP 1 LAST VALUE 10.0K
J 0
(-5005 3825);
DISPLAY 0.617021 (-5005 3825);
PAINT SKYBLUE (-5005 3825);
FORCEPROP 1 LAST PART_NUMBER G21796-016
J 0
(-5010 3625);
DISPLAY 0.617021 (-5010 3625);
PAINT BLUE (-5010 3625);
FORCEPROP 1 LAST LOCATION R8D16
J 0
(-5005 3875);
DISPLAY 0.617021 (-5005 3875);
PAINT AQUA (-5005 3875);
FORCEPROP 2 LAST CDS_LIB mstr_discrete
J 0
(-5050 3750);
PAINT MONO (-5050 3750);
DISPLAY INVISIBLE (-5050 3750);
FORCEPROP 1 LAST PATH I71
J 0
(-5000 3925);
DISPLAY 0.978723 (-5000 3925);
PAINT WHITE (-5000 3925);
DISPLAY INVISIBLE (-5000 3925);
FORCEPROP 2 LAST CDS_LOCATION R8D16
J 0
(-5005 3875);
DISPLAY 0.617021 (-5005 3875);
PAINT AQUA (-5005 3875);
DISPLAY INVISIBLE (-5005 3875);
FORCEPROP 2 LAST ROOM SB
J 0
(-5000 3925);
DISPLAY 1.361702 (-5000 3925);
PAINT ORANGE (-5000 3925);
DISPLAY INVISIBLE (-5000 3925);
FORCEPROP 2 LAST BOM_COST SB
J 0
(-5000 3925);
DISPLAY 1.361702 (-5000 3925);
PAINT ORANGE (-5000 3925);
DISPLAY INVISIBLE (-5000 3925);
FORCEPROP 2 LAST SEC 1
J 0
(-5000 3975);
DISPLAY 0.680851 (-5000 3975);
PAINT MONO (-5000 3975);
DISPLAY INVISIBLE (-5000 3975);
FORCEPROP 2 LAST SEC_TYPE 0402
J 0
(-5000 3975);
DISPLAY 1.021277 (-5000 3975);
PAINT ORANGE (-5000 3975);
DISPLAY INVISIBLE (-5000 3975);
FORCEADD RES..2
(400 4600);
FORCEPROP 1 LASTPIN (400 4500) $PN 2
J 0
(405 4510);
DISPLAY 0.617021 (405 4510);
PAINT ORANGE (405 4510);
FORCEPROP 1 LASTPIN (400 4700) $PN 1
J 0
(405 4662);
DISPLAY 0.617021 (405 4662);
PAINT ORANGE (405 4662);
FORCEPROP 1 LAST TOLERANCE 1%
J 0
(445 4625);
DISPLAY 0.617021 (445 4625);
PAINT SKYBLUE (445 4625);
FORCEPROP 1 LAST WATTAGE 1/16W
J 0
(440 4575);
DISPLAY 0.617021 (440 4575);
PAINT SKYBLUE (440 4575);
FORCEPROP 1 LAST PACK_TYPE 0402
J 0
(440 4425);
DISPLAY 0.617021 (440 4425);
PAINT SKYBLUE (440 4425);
FORCEPROP 1 LAST VALUE 4.75K
J 0
(445 4675);
DISPLAY 0.617021 (445 4675);
PAINT SKYBLUE (445 4675);
FORCEPROP 1 LAST PART_NUMBER G21796-072
J 0
(440 4475);
DISPLAY 0.617021 (440 4475);
PAINT BLUE (440 4475);
FORCEPROP 1 LAST LOCATION R3N2
J 0
(445 4725);
DISPLAY 0.617021 (445 4725);
PAINT AQUA (445 4725);
FORCEPROP 1 LAST MATERIAL EMPTY
J 0
(440 4525);
DISPLAY 0.617021 (440 4525);
PAINT RED (440 4525);
FORCEPROP 2 LAST CDS_LIB mstr_discrete
J 0
(400 4600);
PAINT ORANGE (400 4600);
DISPLAY INVISIBLE (400 4600);
FORCEPROP 2 LAST ROOM BMC_MISC
J 0
(350 4700);
DISPLAY 1.021277 (350 4700);
PAINT ORANGE (350 4700);
DISPLAY INVISIBLE (350 4700);
FORCEPROP 2 LAST BOM_COST SB
J 0
(350 4750);
DISPLAY 1.021277 (350 4750);
PAINT ORANGE (350 4750);
DISPLAY INVISIBLE (350 4750);
FORCEPROP 2 LAST CDS_LOCATION R3N2
J 0
(445 4725);
DISPLAY 0.617021 (445 4725);
PAINT AQUA (445 4725);
DISPLAY INVISIBLE (445 4725);
FORCEPROP 1 LAST PATH I72
J 0
(450 4775);
DISPLAY 0.978723 (450 4775);
PAINT WHITE (450 4775);
DISPLAY INVISIBLE (450 4775);
FORCEPROP 2 LAST SEC 1
J 0
(450 4825);
DISPLAY 0.680851 (450 4825);
PAINT MONO (450 4825);
DISPLAY INVISIBLE (450 4825);
FORCEPROP 2 LAST SEC_TYPE 0402
J 0
(450 4825);
DISPLAY 1.021277 (450 4825);
PAINT ORANGE (450 4825);
DISPLAY INVISIBLE (450 4825);
FORCEADD OFFPAGE..2
(1550 4325);
FORCEPROP 2 LAST $XR0 144 
J 0
(1739 4325);
DISPLAY 0.638298 (1739 4325);
PAINT MONO (1739 4325);
FORCEPROP 2 LAST $XR1 121 
J 0
(1859 4325);
DISPLAY 0.638298 (1859 4325);
PAINT MONO (1859 4325);
FORCEPROP 1 LAST COMMENT_BODY TRUE
J 0
(1505 4230);
DISPLAY 0.872340 (1505 4230);
PAINT GREEN (1505 4230);
DISPLAY INVISIBLE (1505 4230);
FORCEPROP 2 LAST CDS_LIB mstr_standard
J 0
(1550 4325);
PAINT ORANGE (1550 4325);
DISPLAY INVISIBLE (1550 4325);
FORCEPROP 2 LAST PATH I73
J 0
(1875 4375);
DISPLAY 1.021277 (1875 4375);
PAINT ORANGE (1875 4375);
DISPLAY INVISIBLE (1875 4375);
FORCEPROP 1 LAST OFFPAGE TRUE
J 0
(1875 4200);
DISPLAY 0.872340 (1875 4200);
PAINT GREEN (1875 4200);
DISPLAY INVISIBLE (1875 4200);
FORCEADD P3V3_STBY..1
(400 4900);
FORCEPROP 3 LASTPIN (400 4850) SIG_NAME P3V3_STBY\g
J 0
(410 4860);
DISPLAY 0.659574 (410 4860);
PAINT MONO (410 4860);
DISPLAY INVISIBLE (410 4860);
FORCEPROP 1 LAST HDL_POWER P3V3_STBY
J 0
(100 4775);
DISPLAY 0.872340 (100 4775);
PAINT ORANGE (100 4775);
DISPLAY INVISIBLE (100 4775);
FORCEPROP 1 LAST BODY_TYPE PLUMBING
J 0
(355 4857);
DISPLAY 0.340426 (355 4857);
PAINT GREEN (355 4857);
DISPLAY INVISIBLE (355 4857);
FORCEPROP 1 LAST VOLTAGE 3.3V
J 0
(355 4857);
DISPLAY 0.340426 (355 4857);
PAINT SKYBLUE (355 4857);
DISPLAY INVISIBLE (355 4857);
FORCEPROP 1 LAST PATH I74
J 0
(445 4902);
DISPLAY 0.340426 (445 4902);
PAINT GREEN (445 4902);
DISPLAY INVISIBLE (445 4902);
FORCEPROP 2 LAST CDS_LIB mstr_symbols
J 0
(400 4900);
PAINT MONO (400 4900);
DISPLAY INVISIBLE (400 4900);
FORCEPROP 1 LAST SIZE 1B
J 0
(445 4922);
DISPLAY 0.340426 (445 4922);
PAINT GREEN (445 4922);
DISPLAY INVISIBLE (445 4922);
FORCEADD P3V3_STBY..1
(-3350 1600);
FORCEPROP 3 LASTPIN (-3350 1550) SIG_NAME P3V3_STBY\g
J 0
(-3340 1560);
DISPLAY 0.659574 (-3340 1560);
PAINT MONO (-3340 1560);
DISPLAY INVISIBLE (-3340 1560);
FORCEPROP 1 LAST HDL_POWER P3V3_STBY
J 0
(-3650 1475);
DISPLAY 0.872340 (-3650 1475);
PAINT ORANGE (-3650 1475);
DISPLAY INVISIBLE (-3650 1475);
FORCEPROP 1 LAST VOLTAGE 3.3V
J 0
(-3395 1557);
DISPLAY 0.340426 (-3395 1557);
PAINT SKYBLUE (-3395 1557);
DISPLAY INVISIBLE (-3395 1557);
FORCEPROP 2 LAST CDS_LIB mstr_symbols
J 0
(-3350 1600);
PAINT MONO (-3350 1600);
DISPLAY INVISIBLE (-3350 1600);
FORCEPROP 1 LAST BODY_TYPE PLUMBING
J 0
(-3395 1557);
DISPLAY 0.340426 (-3395 1557);
PAINT GREEN (-3395 1557);
DISPLAY INVISIBLE (-3395 1557);
FORCEPROP 1 LAST SIZE 1B
J 0
(-3305 1622);
DISPLAY 0.340426 (-3305 1622);
PAINT GREEN (-3305 1622);
DISPLAY INVISIBLE (-3305 1622);
FORCEPROP 1 LAST PATH I75
J 0
(-3305 1602);
DISPLAY 0.340426 (-3305 1602);
PAINT GREEN (-3305 1602);
DISPLAY INVISIBLE (-3305 1602);
FORCEADD RES..2
(-3350 1375);
FORCEPROP 1 LAST TOLERANCE 1%
J 0
(-3305 1400);
DISPLAY 0.617021 (-3305 1400);
PAINT SKYBLUE (-3305 1400);
FORCEPROP 1 LAST PACK_TYPE 0402
J 0
(-3310 1200);
DISPLAY 0.617021 (-3310 1200);
PAINT SKYBLUE (-3310 1200);
FORCEPROP 1 LAST LOCATION R2U30
J 0
(-3305 1500);
DISPLAY 0.617021 (-3305 1500);
PAINT AQUA (-3305 1500);
FORCEPROP 1 LAST VALUE 4.75K
J 0
(-3305 1450);
DISPLAY 0.617021 (-3305 1450);
PAINT SKYBLUE (-3305 1450);
FORCEPROP 1 LAST WATTAGE 1/16W
J 0
(-3310 1350);
DISPLAY 0.617021 (-3310 1350);
PAINT SKYBLUE (-3310 1350);
FORCEPROP 1 LAST MATERIAL CHIP
J 0
(-3310 1300);
DISPLAY 0.617021 (-3310 1300);
PAINT SKYBLUE (-3310 1300);
FORCEPROP 1 LAST PART_NUMBER G21796-072
J 0
(-3310 1250);
DISPLAY 0.617021 (-3310 1250);
PAINT BLUE (-3310 1250);
FORCEPROP 1 LASTPIN (-3350 1475) $PN 1
J 0
(-3345 1437);
DISPLAY 0.787234 (-3345 1437);
PAINT ORANGE (-3345 1437);
DISPLAY INVISIBLE (-3345 1437);
FORCEPROP 1 LASTPIN (-3350 1275) $PN 2
J 0
(-3345 1285);
DISPLAY 0.787234 (-3345 1285);
PAINT ORANGE (-3345 1285);
DISPLAY INVISIBLE (-3345 1285);
FORCEPROP 2 LAST CDS_LIB mstr_discrete
J 0
(-3350 1375);
PAINT MONO (-3350 1375);
DISPLAY INVISIBLE (-3350 1375);
FORCEPROP 2 LAST CDS_LOCATION R2U30
J 0
(-3305 1500);
DISPLAY 0.617021 (-3305 1500);
PAINT AQUA (-3305 1500);
DISPLAY INVISIBLE (-3305 1500);
FORCEPROP 2 LAST CDS_SEC 1
J 0
(-3300 1600);
PAINT MONO (-3300 1600);
DISPLAY INVISIBLE (-3300 1600);
FORCEPROP 2 LAST $SEC 1
J 0
(-3300 1600);
PAINT MONO (-3300 1600);
DISPLAY INVISIBLE (-3300 1600);
FORCEPROP 1 LAST PATH I76
J 0
(-3300 1550);
DISPLAY 0.978723 (-3300 1550);
PAINT WHITE (-3300 1550);
DISPLAY INVISIBLE (-3300 1550);
FORCEPROP 0 LAST ROOM ADR
J 0
(-3300 1600);
DISPLAY 1.021277 (-3300 1600);
PAINT ORANGE (-3300 1600);
DISPLAY INVISIBLE (-3300 1600);
FORCEADD OFFPAGE..5
(-4075 1175);
FORCEPROP 2 LAST $XR0 119 
J 0
(-4330 1175);
DISPLAY 0.638298 (-4330 1175);
PAINT MONO (-4330 1175);
FORCEPROP 2 LAST $XR1 147 
J 0
(-4450 1175);
DISPLAY 0.638298 (-4450 1175);
PAINT MONO (-4450 1175);
FORCEPROP 2 LAST $XR2 191 
J 0
(-4570 1175);
DISPLAY 0.638298 (-4570 1175);
PAINT MONO (-4570 1175);
FORCEPROP 2 LAST PATH I77
J 0
(-4325 1225);
DISPLAY 1.021277 (-4325 1225);
PAINT ORANGE (-4325 1225);
DISPLAY INVISIBLE (-4325 1225);
FORCEPROP 1 LAST COMMENT_BODY TRUE
J 0
(-3975 1100);
DISPLAY 0.872340 (-3975 1100);
PAINT GREEN (-3975 1100);
DISPLAY INVISIBLE (-3975 1100);
FORCEPROP 1 LAST OFFPAGE TRUE
J 0
(-3750 1050);
DISPLAY 0.872340 (-3750 1050);
PAINT GREEN (-3750 1050);
DISPLAY INVISIBLE (-3750 1050);
FORCEPROP 2 LAST CDS_LIB mstr_standard
J 0
(-4075 1175);
PAINT MONO (-4075 1175);
DISPLAY INVISIBLE (-4075 1175);
FORCEADD RES..2
(1850 1875);
FORCEPROP 1 LAST PACK_TYPE 0402
J 0
(1890 1700);
DISPLAY 0.617021 (1890 1700);
PAINT SKYBLUE (1890 1700);
FORCEPROP 1 LASTPIN (1850 1775) $PN 2
J 0
(1855 1785);
DISPLAY 0.617021 (1855 1785);
PAINT ORANGE (1855 1785);
FORCEPROP 1 LASTPIN (1850 1975) $PN 1
J 0
(1855 1937);
DISPLAY 0.617021 (1855 1937);
PAINT ORANGE (1855 1937);
FORCEPROP 1 LAST WATTAGE 1/16W
J 0
(1890 1850);
DISPLAY 0.617021 (1890 1850);
PAINT SKYBLUE (1890 1850);
FORCEPROP 1 LAST TOLERANCE 1%
J 0
(1895 1900);
DISPLAY 0.617021 (1895 1900);
PAINT SKYBLUE (1895 1900);
FORCEPROP 1 LAST VALUE 1.00K
J 0
(1895 1950);
DISPLAY 0.617021 (1895 1950);
PAINT SKYBLUE (1895 1950);
FORCEPROP 1 LAST LOCATION R3N17
J 0
(1895 2000);
DISPLAY 0.617021 (1895 2000);
PAINT AQUA (1895 2000);
FORCEPROP 1 LAST MATERIAL EMPTY
J 0
(1890 1800);
DISPLAY 0.617021 (1890 1800);
PAINT RED (1890 1800);
FORCEPROP 1 LAST PART_NUMBER G21796-026
J 0
(1890 1750);
DISPLAY 0.617021 (1890 1750);
PAINT BLUE (1890 1750);
FORCEPROP 2 LAST CDS_LIB mstr_discrete
J 0
(1850 1875);
PAINT ORANGE (1850 1875);
DISPLAY INVISIBLE (1850 1875);
FORCEPROP 2 LAST CDS_LOCATION R3N17
J 0
(1895 2000);
DISPLAY 0.617021 (1895 2000);
PAINT AQUA (1895 2000);
DISPLAY INVISIBLE (1895 2000);
FORCEPROP 2 LAST BOM_COST SB
J 0
(1900 2050);
DISPLAY 1.361702 (1900 2050);
PAINT ORANGE (1900 2050);
DISPLAY INVISIBLE (1900 2050);
FORCEPROP 2 LAST SEC_TYPE 0402
J 0
(1900 2100);
DISPLAY 1.021277 (1900 2100);
PAINT ORANGE (1900 2100);
DISPLAY INVISIBLE (1900 2100);
FORCEPROP 2 LAST SEC 1
J 0
(1900 2100);
DISPLAY 0.680851 (1900 2100);
PAINT MONO (1900 2100);
DISPLAY INVISIBLE (1900 2100);
FORCEPROP 1 LAST PATH I78
J 0
(1900 2050);
DISPLAY 0.978723 (1900 2050);
PAINT WHITE (1900 2050);
DISPLAY INVISIBLE (1900 2050);
FORCEPROP 2 LAST ROOM SB
J 0
(1900 2050);
DISPLAY 1.361702 (1900 2050);
PAINT ORANGE (1900 2050);
DISPLAY INVISIBLE (1900 2050);
FORCEADD P3V3_STBY..1
(1850 2125);
FORCEPROP 3 LASTPIN (1850 2075) SIG_NAME P3V3_STBY\g
J 0
(1860 2085);
DISPLAY 0.659574 (1860 2085);
PAINT MONO (1860 2085);
DISPLAY INVISIBLE (1860 2085);
FORCEPROP 1 LAST HDL_POWER P3V3_STBY
J 0
(1550 2000);
DISPLAY 0.872340 (1550 2000);
PAINT ORANGE (1550 2000);
DISPLAY INVISIBLE (1550 2000);
FORCEPROP 1 LAST VOLTAGE 3.3V
J 0
(1805 2082);
DISPLAY 0.340426 (1805 2082);
PAINT SKYBLUE (1805 2082);
DISPLAY INVISIBLE (1805 2082);
FORCEPROP 1 LAST SIZE 1B
J 0
(1895 2147);
DISPLAY 0.340426 (1895 2147);
PAINT GREEN (1895 2147);
DISPLAY INVISIBLE (1895 2147);
FORCEPROP 2 LAST CDS_LIB mstr_symbols
J 0
(1850 2125);
PAINT ORANGE (1850 2125);
DISPLAY INVISIBLE (1850 2125);
FORCEPROP 1 LAST BODY_TYPE PLUMBING
J 0
(1805 2082);
DISPLAY 0.340426 (1805 2082);
PAINT GREEN (1805 2082);
DISPLAY INVISIBLE (1805 2082);
FORCEPROP 1 LAST PATH I79
J 0
(1895 2127);
DISPLAY 0.340426 (1895 2127);
PAINT GREEN (1895 2127);
DISPLAY INVISIBLE (1895 2127);
FORCEADD OFFPAGE..5
(-1975 1350);
FORCEPROP 2 LAST $XR0 119 
J 0
(-2230 1350);
DISPLAY 0.638298 (-2230 1350);
PAINT MONO (-2230 1350);
FORCEPROP 2 LAST $XR1 176 
J 0
(-2350 1350);
DISPLAY 0.638298 (-2350 1350);
PAINT MONO (-2350 1350);
FORCEPROP 2 LAST CDS_LIB mstr_standard
J 0
(-1975 1350);
PAINT ORANGE (-1975 1350);
DISPLAY INVISIBLE (-1975 1350);
FORCEPROP 1 LAST OFFPAGE TRUE
J 0
(-1650 1225);
DISPLAY 0.872340 (-1650 1225);
PAINT GREEN (-1650 1225);
DISPLAY INVISIBLE (-1650 1225);
FORCEPROP 1 LAST COMMENT_BODY TRUE
J 0
(-1875 1275);
DISPLAY 0.872340 (-1875 1275);
PAINT GREEN (-1875 1275);
DISPLAY INVISIBLE (-1875 1275);
FORCEPROP 2 LAST PATH I82
J 0
(-1925 1425);
DISPLAY 1.021277 (-1925 1425);
PAINT ORANGE (-1925 1425);
DISPLAY INVISIBLE (-1925 1425);
FORCEADD RES..2
(-925 1525);
FORCEPROP 1 LASTPIN (-925 1425) $PN 2
J 0
(-920 1435);
DISPLAY 0.617021 (-920 1435);
PAINT ORANGE (-920 1435);
FORCEPROP 1 LAST PACK_TYPE 0402
J 0
(-885 1350);
DISPLAY 0.617021 (-885 1350);
PAINT SKYBLUE (-885 1350);
FORCEPROP 1 LAST WATTAGE 1/16W
J 0
(-885 1500);
DISPLAY 0.617021 (-885 1500);
PAINT SKYBLUE (-885 1500);
FORCEPROP 1 LAST PART_NUMBER G21796-026
J 0
(-885 1400);
DISPLAY 0.617021 (-885 1400);
PAINT BLUE (-885 1400);
FORCEPROP 1 LAST MATERIAL EMPTY
J 0
(-885 1450);
DISPLAY 0.617021 (-885 1450);
PAINT RED (-885 1450);
FORCEPROP 1 LASTPIN (-925 1625) $PN 1
J 0
(-920 1587);
DISPLAY 0.617021 (-920 1587);
PAINT ORANGE (-920 1587);
FORCEPROP 1 LAST TOLERANCE 1%
J 0
(-880 1550);
DISPLAY 0.617021 (-880 1550);
PAINT SKYBLUE (-880 1550);
FORCEPROP 1 LAST VALUE 1.00K
J 0
(-880 1600);
DISPLAY 0.617021 (-880 1600);
PAINT SKYBLUE (-880 1600);
FORCEPROP 1 LAST LOCATION R2N14
J 0
(-880 1650);
DISPLAY 0.617021 (-880 1650);
PAINT AQUA (-880 1650);
FORCEPROP 2 LAST CDS_LIB mstr_discrete
J 0
(-925 1525);
PAINT ORANGE (-925 1525);
DISPLAY INVISIBLE (-925 1525);
FORCEPROP 2 LAST CDS_LOCATION R2N14
J 0
(-880 1650);
DISPLAY 0.617021 (-880 1650);
PAINT AQUA (-880 1650);
DISPLAY INVISIBLE (-880 1650);
FORCEPROP 2 LAST BOM_COST SB
J 0
(-875 1700);
DISPLAY 1.361702 (-875 1700);
PAINT ORANGE (-875 1700);
DISPLAY INVISIBLE (-875 1700);
FORCEPROP 0 LAST SEC 1
J 0
(-875 1700);
DISPLAY 0.680851 (-875 1700);
PAINT MONO (-875 1700);
DISPLAY INVISIBLE (-875 1700);
FORCEPROP 1 LAST PATH I83
J 0
(-875 1700);
DISPLAY 0.978723 (-875 1700);
PAINT WHITE (-875 1700);
DISPLAY INVISIBLE (-875 1700);
FORCEPROP 2 LAST ROOM SB
J 0
(-875 1700);
DISPLAY 1.361702 (-875 1700);
PAINT ORANGE (-875 1700);
DISPLAY INVISIBLE (-875 1700);
FORCEPROP 2 LAST SEC_TYPE 0402
J 0
(-875 1750);
DISPLAY 1.021277 (-875 1750);
PAINT ORANGE (-875 1750);
DISPLAY INVISIBLE (-875 1750);
FORCEADD P3V3_STBY..1
(-925 1750);
FORCEPROP 3 LASTPIN (-925 1700) SIG_NAME P3V3_STBY\g
J 0
(-915 1710);
DISPLAY 0.659574 (-915 1710);
PAINT MONO (-915 1710);
DISPLAY INVISIBLE (-915 1710);
FORCEPROP 1 LAST HDL_POWER P3V3_STBY
J 0
(-1225 1625);
DISPLAY 0.872340 (-1225 1625);
PAINT ORANGE (-1225 1625);
DISPLAY INVISIBLE (-1225 1625);
FORCEPROP 1 LAST BODY_TYPE PLUMBING
J 0
(-970 1707);
DISPLAY 0.340426 (-970 1707);
PAINT GREEN (-970 1707);
DISPLAY INVISIBLE (-970 1707);
FORCEPROP 2 LAST CDS_LIB mstr_symbols
J 0
(-925 1750);
PAINT ORANGE (-925 1750);
DISPLAY INVISIBLE (-925 1750);
FORCEPROP 1 LAST VOLTAGE 3.3V
J 0
(-970 1707);
DISPLAY 0.340426 (-970 1707);
PAINT SKYBLUE (-970 1707);
DISPLAY INVISIBLE (-970 1707);
FORCEPROP 1 LAST SIZE 1B
J 0
(-880 1772);
DISPLAY 0.340426 (-880 1772);
PAINT GREEN (-880 1772);
DISPLAY INVISIBLE (-880 1772);
FORCEPROP 1 LAST PATH I84
J 0
(-880 1752);
DISPLAY 0.340426 (-880 1752);
PAINT GREEN (-880 1752);
DISPLAY INVISIBLE (-880 1752);
FORCEADD DESIGN_NOTE..1
(50 4150);
FORCEPROP 0 LAST L3 FLASH DESC OVERRIDE DISABLED WHEN HIGH
J 0
(-125 4000);
DISPLAY 1.361702 (-125 4000);
PAINT ORANGE (-125 4000);
FORCEPROP 0 LAST L2 FLASH DESC OVERRIDE ENABLED WHEN LOW (DEFAULT)
J 0
(-125 3925);
DISPLAY 1.319149 (-125 3925);
PAINT WHITE (-125 3925);
FORCEPROP 0 LAST L1 PCH INTERNAL PULL-DOWN.
J 0
(-125 3850);
DISPLAY 1.319149 (-125 3850);
PAINT WHITE (-125 3850);
FORCEPROP 2 LAST ROOM SB
J 0
(-125 4050);
DISPLAY 1.361702 (-125 4050);
PAINT ORANGE (-125 4050);
DISPLAY INVISIBLE (-125 4050);
FORCEPROP 2 LAST BOM_COST SB
J 0
(-125 4050);
DISPLAY 1.361702 (-125 4050);
PAINT ORANGE (-125 4050);
DISPLAY INVISIBLE (-125 4050);
FORCEPROP 1 LAST COMMENT_BODY TRUE
J 0
(75 4250);
DISPLAY 1.319149 (75 4250);
PAINT ORANGE (75 4250);
DISPLAY INVISIBLE (75 4250);
FORCEPROP 2 LAST CDS_LIB mstr_symbols
J 0
(50 4150);
PAINT MONO (50 4150);
DISPLAY INVISIBLE (50 4150);
FORCEADD DNS..2
(-920 1520);
PAINT RED (-920 1520);
FORCEPROP 1 LAST COMMENT_BODY TRUE
R 1
J 0
(-845 1295);
DISPLAY 0.872340 (-845 1295);
PAINT GREEN (-845 1295);
DISPLAY INVISIBLE (-845 1295);
FORCEPROP 2 LAST CDS_LIB mstr_misc
J 0
(-920 1520);
PAINT ORANGE (-920 1520);
DISPLAY INVISIBLE (-920 1520);
FORCEADD DESIGN_NOTE..1
(-2250 2500);
FORCEPROP 0 LAST L3 BOOT HALT ENABLED WHEN LOW
J 0
(-2425 2350);
DISPLAY 1.361702 (-2425 2350);
PAINT ORANGE (-2425 2350);
FORCEPROP 0 LAST L2 BOOT HALT DISABLE WHEN HIGH (DEFAULT)
J 0
(-2425 2275);
DISPLAY 1.319149 (-2425 2275);
PAINT WHITE (-2425 2275);
FORCEPROP 0 LAST L1 PCH INTERNAL PULL-UP.
J 0
(-2425 2200);
DISPLAY 1.319149 (-2425 2200);
PAINT WHITE (-2425 2200);
FORCEPROP 2 LAST ROOM SB
J 0
(-2425 2400);
DISPLAY 1.361702 (-2425 2400);
PAINT ORANGE (-2425 2400);
DISPLAY INVISIBLE (-2425 2400);
FORCEPROP 1 LAST COMMENT_BODY TRUE
J 0
(-2225 2600);
DISPLAY 1.319149 (-2225 2600);
PAINT ORANGE (-2225 2600);
DISPLAY INVISIBLE (-2225 2600);
FORCEPROP 2 LAST CDS_LIB mstr_symbols
J 0
(-2250 2500);
PAINT ORANGE (-2250 2500);
DISPLAY INVISIBLE (-2250 2500);
FORCEPROP 2 LAST BOM_COST SB
J 0
(-2425 2400);
DISPLAY 1.361702 (-2425 2400);
PAINT ORANGE (-2425 2400);
DISPLAY INVISIBLE (-2425 2400);
FORCEADD DESIGN_NOTE..1
(-2250 4100);
FORCEPROP 0 LAST L1 NO PCH INTERNAL PU/PD
J 0
(-2425 3825);
DISPLAY 1.276596 (-2425 3825);
PAINT ORANGE (-2425 3825);
FORCEPROP 0 LAST L3 ADR TIMER HOLD OFF ENABLED WHEN LOW
J 0
(-2425 3900);
DISPLAY 1.276596 (-2425 3900);
PAINT ORANGE (-2425 3900);
FORCEPROP 0 LAST L2 ADR TIMER HOLD OFF DISABLED WHEN HIGH (DEFAULT)
J 0
(-2425 3975);
DISPLAY 1.276596 (-2425 3975);
PAINT ORANGE (-2425 3975);
FORCEPROP 2 LAST BOM_COST SB
J 0
(-2125 4000);
DISPLAY 1.361702 (-2125 4000);
PAINT ORANGE (-2125 4000);
DISPLAY INVISIBLE (-2125 4000);
FORCEPROP 2 LAST ROOM SB_HEADERS
J 0
(-2125 4000);
DISPLAY 1.361702 (-2125 4000);
PAINT ORANGE (-2125 4000);
DISPLAY INVISIBLE (-2125 4000);
FORCEPROP 2 LAST CDS_LIB mstr_symbols
J 0
(-2250 4100);
PAINT ORANGE (-2250 4100);
DISPLAY INVISIBLE (-2250 4100);
FORCEPROP 1 LAST COMMENT_BODY TRUE
J 0
(-2225 4200);
DISPLAY 1.319149 (-2225 4200);
PAINT ORANGE (-2225 4200);
DISPLAY INVISIBLE (-2225 4200);
FORCEADD DESIGN_NOTE..1
(50 1250);
FORCEPROP 0 LAST L2 PERSONALITY STRAP ENABLE WHEN LOW (DEFAULT)
J 0
(-125 1100);
DISPLAY 1.319149 (-125 1100);
PAINT WHITE (-125 1100);
FORCEPROP 0 LAST L3 PERSONALITY STRAP DISABLE WHEN HIGH
J 0
(-125 1025);
DISPLAY 1.361702 (-125 1025);
PAINT ORANGE (-125 1025);
FORCEPROP 0 LAST L1 PCH INTERNAL PULL-UP.
J 0
(-125 950);
DISPLAY 1.319149 (-125 950);
PAINT WHITE (-125 950);
FORCEPROP 2 LAST ROOM SB
J 0
(-125 1150);
DISPLAY 1.361702 (-125 1150);
PAINT ORANGE (-125 1150);
DISPLAY INVISIBLE (-125 1150);
FORCEPROP 2 LAST BOM_COST SB
J 0
(-125 1150);
DISPLAY 1.361702 (-125 1150);
PAINT ORANGE (-125 1150);
DISPLAY INVISIBLE (-125 1150);
FORCEPROP 1 LAST COMMENT_BODY TRUE
J 0
(75 1350);
DISPLAY 1.319149 (75 1350);
PAINT ORANGE (75 1350);
DISPLAY INVISIBLE (75 1350);
FORCEPROP 2 LAST CDS_LIB mstr_symbols
J 0
(50 1250);
PAINT ORANGE (50 1250);
DISPLAY INVISIBLE (50 1250);
FORCEADD DESIGN_NOTE..1
(-2200 1150);
FORCEPROP 0 LAST L3 BOOT LPC/ESPI WHEN HIGH
J 0
(-2375 950);
DISPLAY 1.276596 (-2375 950);
PAINT ORANGE (-2375 950);
FORCEPROP 0 LAST L2 BOOT SPI WHEN LOW (DEFAULT)
J 0
(-2375 1025);
DISPLAY 1.276596 (-2375 1025);
PAINT ORANGE (-2375 1025);
FORCEPROP 0 LAST L1 PCH HAS INTERNAL PULL-DOWN
J 0
(-2375 875);
DISPLAY 1.319149 (-2375 875);
PAINT WHITE (-2375 875);
FORCEPROP 2 LAST CDS_LIB mstr_symbols
J 0
(-2200 1150);
PAINT ORANGE (-2200 1150);
DISPLAY INVISIBLE (-2200 1150);
FORCEPROP 2 LAST ROOM SB_HEADERS
J 0
(-2075 1050);
DISPLAY 1.361702 (-2075 1050);
PAINT ORANGE (-2075 1050);
DISPLAY INVISIBLE (-2075 1050);
FORCEPROP 1 LAST COMMENT_BODY TRUE
J 0
(-2175 1250);
DISPLAY 1.319149 (-2175 1250);
PAINT ORANGE (-2175 1250);
DISPLAY INVISIBLE (-2175 1250);
FORCEPROP 2 LAST BOM_COST SB
J 0
(-2075 1050);
DISPLAY 1.361702 (-2075 1050);
PAINT ORANGE (-2075 1050);
DISPLAY INVISIBLE (-2075 1050);
FORCEADD DNS..2
(1755 3045);
PAINT RED (1755 3045);
FORCEPROP 1 LAST COMMENT_BODY TRUE
R 1
J 0
(1830 2820);
DISPLAY 0.872340 (1830 2820);
PAINT GREEN (1830 2820);
DISPLAY INVISIBLE (1830 2820);
FORCEPROP 2 LAST CDS_LIB mstr_misc
J 0
(1755 3045);
PAINT ORANGE (1755 3045);
DISPLAY INVISIBLE (1755 3045);
FORCEADD DNS..2
(-945 3145);
PAINT RED (-945 3145);
FORCEPROP 1 LAST COMMENT_BODY TRUE
R 1
J 0
(-870 2920);
DISPLAY 0.872340 (-870 2920);
PAINT GREEN (-870 2920);
DISPLAY INVISIBLE (-870 2920);
FORCEPROP 2 LAST CDS_LIB mstr_misc
J 0
(-945 3145);
PAINT ORANGE (-945 3145);
DISPLAY INVISIBLE (-945 3145);
FORCEADD DNS..2
(-945 2745);
PAINT RED (-945 2745);
FORCEPROP 1 LAST COMMENT_BODY TRUE
R 1
J 0
(-870 2520);
DISPLAY 0.872340 (-870 2520);
PAINT GREEN (-870 2520);
DISPLAY INVISIBLE (-870 2520);
FORCEPROP 2 LAST CDS_LIB mstr_misc
J 0
(-945 2745);
PAINT ORANGE (-945 2745);
DISPLAY INVISIBLE (-945 2745);
FORCEADD DNS..2
(-3220 2195);
PAINT RED (-3220 2195);
FORCEPROP 1 LAST COMMENT_BODY TRUE
R 1
J 0
(-3145 1970);
DISPLAY 0.872340 (-3145 1970);
PAINT GREEN (-3145 1970);
DISPLAY INVISIBLE (-3145 1970);
FORCEPROP 2 LAST CDS_LIB mstr_misc
J 0
(-3220 2195);
PAINT ORANGE (-3220 2195);
DISPLAY INVISIBLE (-3220 2195);
FORCEADD DESIGN_NOTE..1
(-5025 4650);
FORCEPROP 0 LAST L2 PCH HAS INTERNAL PULL-DOWN
J 0
(-5225 4375);
DISPLAY 1.276596 (-5225 4375);
PAINT ORANGE (-5225 4375);
FORCEPROP 0 LAST L1 GBE DEBUG MODE IS ENABLED WHEN HIGH
J 0
(-5225 4450);
DISPLAY 1.319149 (-5225 4450);
PAINT WHITE (-5225 4450);
FORCEPROP 0 LAST L3 GBE DEBUG MODE IS DISABLED WHEN LOW (DEFAULT)
J 0
(-5225 4525);
DISPLAY 1.276596 (-5225 4525);
PAINT ORANGE (-5225 4525);
FORCEPROP 2 LAST ROOM SB
J 0
(-5200 4550);
DISPLAY 1.361702 (-5200 4550);
PAINT ORANGE (-5200 4550);
DISPLAY INVISIBLE (-5200 4550);
FORCEPROP 2 LAST BOM_COST SB
J 0
(-5200 4550);
DISPLAY 1.361702 (-5200 4550);
PAINT ORANGE (-5200 4550);
DISPLAY INVISIBLE (-5200 4550);
FORCEPROP 1 LAST COMMENT_BODY TRUE
J 0
(-5000 4750);
DISPLAY 1.319149 (-5000 4750);
PAINT ORANGE (-5000 4750);
DISPLAY INVISIBLE (-5000 4750);
FORCEPROP 2 LAST CDS_LIB mstr_symbols
J 0
(-5025 4650);
PAINT ORANGE (-5025 4650);
DISPLAY INVISIBLE (-5025 4650);
FORCEADD DNS..2
(-920 4445);
PAINT RED (-920 4445);
FORCEPROP 1 LAST COMMENT_BODY TRUE
R 1
J 0
(-845 4220);
DISPLAY 0.872340 (-845 4220);
PAINT GREEN (-845 4220);
DISPLAY INVISIBLE (-845 4220);
FORCEPROP 2 LAST CDS_LIB mstr_misc
J 0
(-920 4445);
PAINT ORANGE (-920 4445);
DISPLAY INVISIBLE (-920 4445);
FORCEADD DESIGN_NOTE..1
(-4500 3375);
FORCEPROP 0 LAST L2 PCH HAS INTERNAL PULL-DOWN
J 0
(-4700 3100);
DISPLAY 1.276596 (-4700 3100);
PAINT ORANGE (-4700 3100);
FORCEPROP 0 LAST L3 GBE AUX POWER IS DISABLED WHEN LOW (DEFAULT)
J 0
(-4700 3250);
DISPLAY 1.276596 (-4700 3250);
PAINT ORANGE (-4700 3250);
FORCEPROP 0 LAST L1 GBE AUX POWER IS ENABLED WHEN HIGH
J 0
(-4700 3175);
DISPLAY 1.276596 (-4700 3175);
PAINT ORANGE (-4700 3175);
FORCEPROP 1 LAST COMMENT_BODY TRUE
J 0
(-4475 3475);
DISPLAY 0.978723 (-4475 3475);
PAINT ORANGE (-4475 3475);
DISPLAY INVISIBLE (-4475 3475);
FORCEPROP 2 LAST CDS_LIB mstr_symbols
J 0
(-4500 3375);
PAINT MONO (-4500 3375);
DISPLAY INVISIBLE (-4500 3375);
FORCEADD DNS..2
(-5045 3745);
PAINT RED (-5045 3745);
FORCEPROP 1 LAST COMMENT_BODY TRUE
R 1
J 0
(-4970 3520);
DISPLAY 0.872340 (-4970 3520);
PAINT GREEN (-4970 3520);
DISPLAY INVISIBLE (-4970 3520);
FORCEPROP 2 LAST CDS_LIB mstr_misc
J 0
(-5045 3745);
PAINT ORANGE (-5045 3745);
DISPLAY INVISIBLE (-5045 3745);
FORCEADD DNS..2
(405 4595);
PAINT RED (405 4595);
FORCEPROP 1 LAST COMMENT_BODY TRUE
R 1
J 0
(480 4370);
DISPLAY 0.872340 (480 4370);
PAINT GREEN (480 4370);
DISPLAY INVISIBLE (480 4370);
FORCEPROP 2 LAST CDS_LIB mstr_misc
J 0
(405 4595);
PAINT ORANGE (405 4595);
DISPLAY INVISIBLE (405 4595);
FORCEADD DNS..2
(1855 1870);
PAINT RED (1855 1870);
FORCEPROP 1 LAST COMMENT_BODY TRUE
R 1
J 0
(1930 1645);
DISPLAY 0.872340 (1930 1645);
PAINT GREEN (1930 1645);
DISPLAY INVISIBLE (1930 1645);
FORCEPROP 2 LAST CDS_LIB mstr_misc
J 0
(1855 1870);
PAINT ORANGE (1855 1870);
DISPLAY INVISIBLE (1855 1870);
FORCEADD DESIGN_NOTE..1
(-5050 2200);
FORCEPROP 0 LAST L1 PCH INTERNAL PULL-DOWN.
J 0
(-5250 1900);
DISPLAY 1.319149 (-5250 1900);
PAINT WHITE (-5250 1900);
FORCEPROP 0 LAST L2 TLS ENABLED WHEN HIGH (DEFAULT)
J 0
(-5250 2050);
DISPLAY 1.319149 (-5250 2050);
PAINT WHITE (-5250 2050);
FORCEPROP 0 LAST L3 TLS DISABLED WHEN LOW
J 0
(-5250 1975);
DISPLAY 1.276596 (-5250 1975);
PAINT ORANGE (-5250 1975);
FORCEPROP 2 LAST ROOM SB
J 0
(-5225 2100);
DISPLAY 1.361702 (-5225 2100);
PAINT ORANGE (-5225 2100);
DISPLAY INVISIBLE (-5225 2100);
FORCEPROP 2 LAST BOM_COST SB
J 0
(-5225 2100);
DISPLAY 1.361702 (-5225 2100);
PAINT ORANGE (-5225 2100);
DISPLAY INVISIBLE (-5225 2100);
FORCEPROP 1 LAST COMMENT_BODY TRUE
J 0
(-5025 2300);
DISPLAY 1.319149 (-5025 2300);
PAINT ORANGE (-5025 2300);
DISPLAY INVISIBLE (-5025 2300);
FORCEPROP 2 LAST CDS_LIB mstr_symbols
J 0
(-5050 2200);
PAINT ORANGE (-5050 2200);
DISPLAY INVISIBLE (-5050 2200);
FORCEADD DESIGN_NOTE..1
(175 2850);
FORCEPROP 0 LAST L3 CONSENT STRAP ENABLED WHEN LOW
J 0
(0 2700);
DISPLAY 1.361702 (0 2700);
PAINT ORANGE (0 2700);
FORCEPROP 0 LAST L2 CONSENT STRAP DISABLED WHEN HIGH (DEFAULT)
J 0
(0 2625);
DISPLAY 1.319149 (0 2625);
PAINT WHITE (0 2625);
FORCEPROP 0 LAST L1 PCH INTERNAL PULL-UP.
J 0
(0 2550);
DISPLAY 1.319149 (0 2550);
PAINT WHITE (0 2550);
FORCEPROP 2 LAST ROOM SB
J 0
(0 2750);
DISPLAY 1.361702 (0 2750);
PAINT ORANGE (0 2750);
DISPLAY INVISIBLE (0 2750);
FORCEPROP 2 LAST BOM_COST SB
J 0
(0 2750);
DISPLAY 1.361702 (0 2750);
PAINT ORANGE (0 2750);
DISPLAY INVISIBLE (0 2750);
FORCEPROP 1 LAST COMMENT_BODY TRUE
J 0
(200 2950);
DISPLAY 1.319149 (200 2950);
PAINT ORANGE (200 2950);
DISPLAY INVISIBLE (200 2950);
FORCEPROP 2 LAST CDS_LIB mstr_symbols
J 0
(175 2850);
PAINT ORANGE (175 2850);
DISPLAY INVISIBLE (175 2850);
FORCEADD DESIGN_NOTE..1
(-5000 1025);
FORCEPROP 0 LAST L2 NO REBOOT ENABLED WHEN HIGH (DEFAULT)
J 0
(-5200 875);
DISPLAY 1.319149 (-5200 875);
PAINT WHITE (-5200 875);
FORCEPROP 0 LAST L3 NO REBOOT DISABLED WHEN LOW
J 0
(-5200 800);
DISPLAY 1.276596 (-5200 800);
PAINT ORANGE (-5200 800);
FORCEPROP 0 LAST L1 PCH INTERNAL PULL-DOWN.
J 0
(-5200 725);
DISPLAY 1.319149 (-5200 725);
PAINT WHITE (-5200 725);
FORCEPROP 0 LAST L4 NORMAL UV ADR TRIGGER ENABLE FUNCTIONALITY RESUMES AFTER PLTRST# DEASSERTS
J 0
(-5200 675);
DISPLAY 0.808511 (-5200 675);
PAINT ORANGE (-5200 675);
FORCEPROP 2 LAST ROOM SB
J 0
(-5175 925);
DISPLAY 1.361702 (-5175 925);
PAINT ORANGE (-5175 925);
DISPLAY INVISIBLE (-5175 925);
FORCEPROP 2 LAST BOM_COST SB
J 0
(-5175 925);
DISPLAY 1.361702 (-5175 925);
PAINT ORANGE (-5175 925);
DISPLAY INVISIBLE (-5175 925);
FORCEPROP 2 LAST CDS_LIB mstr_symbols
J 0
(-5000 1025);
PAINT ORANGE (-5000 1025);
DISPLAY INVISIBLE (-5000 1025);
FORCEPROP 1 LAST COMMENT_BODY TRUE
J 0
(-4975 1125);
DISPLAY 1.319149 (-4975 1125);
PAINT ORANGE (-4975 1125);
DISPLAY INVISIBLE (-4975 1125);
FORCEADD DNS..2
(-3270 4970);
PAINT RED (-3270 4970);
FORCEPROP 1 LAST COMMENT_BODY TRUE
R 1
J 0
(-3195 4745);
DISPLAY 0.872340 (-3195 4745);
PAINT GREEN (-3195 4745);
DISPLAY INVISIBLE (-3195 4745);
FORCEPROP 2 LAST CDS_LIB mstr_misc
J 0
(-3270 4970);
PAINT ORANGE (-3270 4970);
DISPLAY INVISIBLE (-3270 4970);
FORCEADD INTEL_CORP_BPAGE..1
(2650 500);
FORCEPROP 1 LAST CDS_CON_LAST_MODIFIED Tue Dec 01 11:51:59 2015
J 0
(1225 825);
PAINT ORANGE (1225 825);
DISPLAY INVISIBLE (1225 825);
FORCEPROP 1 LAST CUSTOM_TXT_CDS <CURRENT_DESIGN_SHEET> OF <TOTAL_DESIGN_SHEETS>
J 0
(2150 525);
PAINT GREEN (2150 525);
FORCEPROP 1 LAST CUSTOM_TXT_CDS <CON_LAST_MODIFIED>
J 0
(725 850);
PAINT GREEN (725 850);
FORCEPROP 2 LAST CUSTOM_TXT_CDS <XR_PAGE_TITLE>
J 0
(-5240 5750);
DISPLAY 0.638298 (-5240 5750);
PAINT PINK (-5240 5750);
DISPLAY INVISIBLE (-5240 5750);
FORCEPROP 1 LAST SCH_TITLE PCH STRAPS (1/2)
J 0
(-5300 550);
DISPLAY 1.212766 (-5300 550);
PAINT ORANGE (-5300 550);
FORCEPROP 1 LAST SCH_ADDRESS1 2200 Mission College Blvd.
J 0
(-1325 625);
DISPLAY 0.617021 (-1325 625);
PAINT GREEN (-1325 625);
FORCEPROP 1 LAST SCH_ADDRESS2 P.O. BOX 58119
J 0
(-1325 575);
DISPLAY 0.617021 (-1325 575);
PAINT GREEN (-1325 575);
FORCEPROP 1 LAST SCH_ADDRESS3 Santa Clara, CA 95052-8119
J 0
(-1325 525);
DISPLAY 0.617021 (-1325 525);
PAINT GREEN (-1325 525);
FORCEPROP 1 LAST SCH_NUMBER H4694802
J 0
(1350 650);
DISPLAY 1.212766 (1350 650);
PAINT YELLOW (1350 650);
FORCEPROP 1 LAST SCH_DEPT BESD
J 1
(-1800 600);
DISPLAY 1.212766 (-1800 600);
PAINT YELLOW (-1800 600);
FORCEPROP 1 LAST SCH_REV 2.420
J 0
(2400 650);
DISPLAY 0.978723 (2400 650);
PAINT YELLOW (2400 650);
FORCEPROP 2 LAST PAGE_BORDER TRUE
J 0
(-5240 5750);
DISPLAY 0.851064 (-5240 5750);
PAINT PINK (-5240 5750);
DISPLAY INVISIBLE (-5240 5750);
FORCEPROP 2 LAST BOM_COST ST_SATA
J 0
(-5225 5800);
PAINT MONO (-5225 5800);
DISPLAY INVISIBLE (-5225 5800);
FORCEPROP 1 LAST COMMENT_BODY TRUE
J 0
(2662 512);
DISPLAY 0.468085 (2662 512);
PAINT GREEN (2662 512);
DISPLAY INVISIBLE (2662 512);
FORCEPROP 2 LAST CDS_LIB mstr_symbols
J 0
(2650 500);
PAINT MONO (2650 500);
DISPLAY INVISIBLE (2650 500);
FORCEPROP 2 LAST CDS_XR_PAGE_TITLE CR-125 : @BASEBOARD_FAB2_LIB.BASEBOARD_FAB2(SCH_1):PAGE125
J 0
(-5240 5750);
DISPLAY 0.638298 (-5240 5750);
PAINT PINK (-5240 5750);
DISPLAY INVISIBLE (-5240 5750);
WIRE 16 -1 (1750 2950)(1750 2850);
WIRE 16 -1 (1850 1375)(1850 1275);
WIRE 16 -1 (-950 2650)(-950 2550);
WIRE 16 -1 (-950 3325)(-950 3250);
WIRE 16 -1 (-3225 2700)(-3225 2625);
WIRE 16 -1 (-925 5050)(-925 5025);
WIRE 16 -1 (-925 4350)(-925 4250);
WIRE 16 -1 (-3225 2100)(-3225 2050);
WIRE 16 -1 (-3275 5150)(-3275 5075);
WIRE 16 -1 (-5050 3925)(-5050 3850);
WIRE 16 -1 (-5050 3275)(-5050 3225);
WIRE 16 -1 (400 4700)(400 4850);
WIRE 16 -1 (-3350 1475)(-3350 1550);
WIRE 16 -1 (1850 1975)(1850 2075);
WIRE 16 -1 (-925 1625)(-925 1700);
WIRE 16 273 (-225 3775)(2600 3775);
WIRE 16 273 (-225 3775)(-225 5450);
WIRE 16 273 (-225 3750)(-225 3775);
WIRE 16 273 (-225 2100)(-225 3750);
WIRE 16 273 (-2600 3750)(-225 3750);
WIRE 16 273 (-2600 3750)(-2600 4300);
WIRE 16 273 (-2600 3050)(-2600 3750);
WIRE 16 273 (-225 825)(-225 2100);
WIRE 16 273 (-2600 2100)(-225 2100);
WIRE 16 273 (-2600 3050)(-2600 2100);
WIRE 16 273 (-2600 1825)(-2600 2100);
WIRE 16 273 (-2600 3050)(-5225 3050);
WIRE 16 273 (-2600 4300)(-2600 5400);
WIRE 16 273 (-5275 4300)(-2600 4300);
WIRE 16 273 (-2600 550)(-2600 1825);
WIRE 16 273 (-2600 1825)(-5275 1825);
WIRE 16 -1 (400 4325)(1500 4325);
FORCEPROP 2 LAST SIG_NAME FM_FLASH_DESC_OVERRIDE
J 0
(915 4335);
DISPLAY 0.617021 (915 4335);
PAINT ORANGE (915 4335);
WIRE 16 -1 (400 4325)(400 4500);
WIRE 16 -1 (1750 3150)(1750 3275);
WIRE 16 -1 (700 3275)(1750 3275);
FORCEPROP 0 LAST SIG_NAME SPI_PCH_IO2
J 0
(850 3285);
DISPLAY 0.617021 (850 3285);
PAINT ORANGE (850 3285);
WIRE 16 -1 (1850 1575)(1850 1700);
WIRE 16 -1 (1850 1700)(1850 1775);
WIRE 16 -1 (975 1700)(1850 1700);
FORCEPROP 0 LAST SIG_NAME SPI_PCH_IO3
J 0
(1125 1710);
DISPLAY 0.617021 (1125 1710);
PAINT ORANGE (1125 1710);
WIRE 16 273 (-200 2475)(2625 2475);
WIRE 16 -1 (-925 4550)(-925 4675);
WIRE 16 -1 (-925 4825)(-925 4675);
WIRE 16 -1 (-1750 4675)(-925 4675);
FORCEPROP 0 LAST SIG_NAME PU_ADR_TIMER_HOLD_OFF_N
J 0
(-1735 4685);
DISPLAY 0.617021 (-1735 4685);
PAINT ORANGE (-1735 4685);
WIRE 16 -1 (-3275 4800)(-3275 4875);
WIRE 16 -1 (-4025 4800)(-3275 4800);
FORCEPROP 2 LAST SIG_NAME RMII_BMC_PCH_SPRNGVLLE_RXER
J 0
(-4035 4810);
DISPLAY 0.617021 (-4035 4810);
PAINT ORANGE (-4035 4810);
WIRE 16 -1 (-950 2850)(-950 2975);
WIRE 16 -1 (-950 2975)(-950 3050);
WIRE 16 -1 (-1400 2975)(-950 2975);
FORCEPROP 0 LAST SIG_NAME SPI_PCH_MOSI
J 0
(-1375 2985);
DISPLAY 0.617021 (-1375 2985);
PAINT ORANGE (-1375 2985);
WIRE 16 -1 (-925 1350)(-925 1425);
WIRE 16 -1 (-925 1350)(-1925 1350);
FORCEPROP 0 LAST SIG_NAME FM_USB_P0_EN_BOOT_BIOS_STRAP_N
J 0
(-1785 1360);
DISPLAY 0.617021 (-1785 1360);
PAINT ORANGE (-1785 1360);
WIRE 16 -1 (-3225 2300)(-3225 2350);
WIRE 16 -1 (-3225 2350)(-3225 2425);
WIRE 16 -1 (-4175 2350)(-3225 2350);
FORCEPROP 0 LAST SIG_NAME PU_PCH_TLS_ENABLE_STRAP
J 2
(-3360 2360);
DISPLAY 0.617021 (-3360 2360);
PAINT ORANGE (-3360 2360);
WIRE 16 -1 (-3350 1175)(-3350 1275);
WIRE 16 -1 (-3350 1175)(-4025 1175);
FORCEPROP 2 LAST SIG_NAME FM_UV_ADR_TRIGGER_EN
J 0
(-3985 1185);
DISPLAY 0.617021 (-3985 1185);
PAINT ORANGE (-3985 1185);
WIRE 16 -1 (-5050 3650)(-5050 3575);
WIRE 16 -1 (-3900 3575)(-5050 3575);
FORCEPROP 0 LAST SIG_NAME RMII_PCH_SPRNGVLLE_ARB_OUT
J 0
(-4685 3585);
DISPLAY 0.617021 (-4685 3585);
PAINT ORANGE (-4685 3585);
WIRE 16 -1 (-5050 3475)(-5050 3575);
DOT 1 (1850 1700);
DOT 1 (-925 4675);
DOT 1 (-2600 4300);
DOT 1 (-225 3775);
DOT 1 (-225 3750);
DOT 1 (-225 2100);
DOT 1 (-950 2975);
DOT 1 (-2600 3750);
DOT 1 (-2600 3050);
DOT 1 (-2600 2100);
DOT 1 (-3225 2350);
DOT 1 (-2600 1825);
DOT 1 (-5050 3575);
FORCENOTE
ROOM=SB
(1975 5300) 0;
DISPLAY LEFT (1975 5300);
DISPLAY 1.723404 (1975 5300);
PAINT PURPLE (1975 5300);
FORCENOTE
GBE DEBUG ENABLE
(-5275 5225) 0;
DISPLAY LEFT (-5275 5225);
DISPLAY 2.680851 (-5275 5225);
PAINT PURPLE (-5275 5225);
FORCENOTE
GBE AUX POWER
(-5250 4100) 0;
DISPLAY LEFT (-5250 4100);
DISPLAY 2.680851 (-5250 4100);
PAINT PURPLE (-5250 4100);
FORCENOTE
BOM_COST=SB
(1725 5150) 0;
DISPLAY LEFT (1725 5150);
DISPLAY 1.723404 (1725 5150);
PAINT PURPLE (1725 5150);
FORCENOTE
0
(2250 3950) 0;
DISPLAY LEFT (2250 3950);
DISPLAY 8.255319 (2250 3950);
PAINT PURPLE (2250 3950);
FORCENOTE
1
(2275 3275) 0;
DISPLAY LEFT (2275 3275);
DISPLAY 8.255319 (2275 3275);
PAINT PURPLE (2275 3275);
FORCENOTE
0
(2250 2025) 0;
DISPLAY LEFT (2250 2025);
DISPLAY 8.255319 (2250 2025);
PAINT PURPLE (2250 2025);
FORCENOTE
CONSENT STRAP 
(125 3575) 0;
DISPLAY LEFT (125 3575);
DISPLAY 2.680851 (125 3575);
PAINT PURPLE (125 3575);
FORCENOTE
OVERRIDE
(-125 5150) 0;
DISPLAY LEFT (-125 5150);
DISPLAY 2.680851 (-125 5150);
PAINT PURPLE (-125 5150);
FORCENOTE
FLASH DESCRIPTOR
(-150 5300) 0;
DISPLAY LEFT (-150 5300);
DISPLAY 2.680851 (-150 5300);
PAINT PURPLE (-150 5300);
FORCENOTE
PERSONALITY STRAP
(-125 2300) 0;
DISPLAY LEFT (-125 2300);
DISPLAY 2.680851 (-125 2300);
PAINT PURPLE (-125 2300);
FORCENOTE
1
(-575 5025) 0;
DISPLAY LEFT (-575 5025);
DISPLAY 8.255319 (-575 5025);
PAINT PURPLE (-575 5025);
FORCENOTE
ADR TIMER OFF
(-2500 5275) 0;
DISPLAY LEFT (-2500 5275);
DISPLAY 2.680851 (-2500 5275);
PAINT PURPLE (-2500 5275);
FORCENOTE
0
(-2975 5050) 0;
DISPLAY LEFT (-2975 5050);
DISPLAY 8.255319 (-2975 5050);
PAINT PURPLE (-2975 5050);
FORCENOTE
0
(-3000 3850) 0;
DISPLAY LEFT (-3000 3850);
DISPLAY 8.255319 (-3000 3850);
PAINT PURPLE (-3000 3850);
FORCENOTE
1
(-625 3300) 0;
DISPLAY LEFT (-625 3300);
DISPLAY 8.255319 (-625 3300);
PAINT PURPLE (-625 3300);
FORCENOTE
0
(-550 1675) 0;
DISPLAY LEFT (-550 1675);
DISPLAY 8.255319 (-550 1675);
PAINT PURPLE (-550 1675);
FORCENOTE
BOOT BIOS DEVICE
(-2475 1900) 0;
DISPLAY LEFT (-2475 1900);
DISPLAY 2.680851 (-2475 1900);
PAINT PURPLE (-2475 1900);
FORCENOTE
BOOT HALT
(-2500 3525) 0;
DISPLAY LEFT (-2500 3525);
DISPLAY 2.680851 (-2500 3525);
PAINT PURPLE (-2500 3525);
FORCENOTE
1
(-2950 2625) 0;
DISPLAY LEFT (-2950 2625);
DISPLAY 8.255319 (-2950 2625);
PAINT PURPLE (-2950 2625);
FORCENOTE
1
(-2975 1350) 0;
DISPLAY LEFT (-2975 1350);
DISPLAY 8.255319 (-2975 1350);
PAINT PURPLE (-2975 1350);
FORCENOTE
NO REBOOT
(-5225 1625) 0;
DISPLAY LEFT (-5225 1625);
DISPLAY 2.680851 (-5225 1625);
PAINT PURPLE (-5225 1625);
FORCENOTE
TLS CONFIDENTIALITY
(-5275 2850) 0;
DISPLAY LEFT (-5275 2850);
DISPLAY 2.680851 (-5275 2850);
PAINT PURPLE (-5275 2850);
QUIT
